FILE_TYPE = MACRO_DRAWING;
SET COLOR_WIRE YELLOW;
SET COLOR_PROP ORANGE;
SET COLOR_DOT WHITE;
SET COLOR_ARC YELLOW;
SET COLOR_BODY GREEN;
SET COLOR_NOTE PURPLE;
SET PROP_DISPLAY VALUE;
SET PAGE_NUMBER P98;
FORCEADD OFFPAGE..5
(-8375 2075);
FORCEPROP 2 LAST $XR0 38 
J 0
(-8629 2075);
DISPLAY 0.638298 (-8629 2075);
PAINT MONO (-8629 2075);
FORCEPROP 2 LAST PATH I1
J 0
(-8575 2125);
DISPLAY 1.021277 (-8575 2125);
DISPLAY INVISIBLE (-8575 2125);
FORCEPROP 1 LAST COMMENT_BODY TRUE
J 0
(-8275 2000);
DISPLAY 0.872340 (-8275 2000);
PAINT GREEN (-8275 2000);
DISPLAY INVISIBLE (-8275 2000);
FORCEPROP 1 LAST OFFPAGE TRUE
J 0
(-8050 1950);
DISPLAY 0.872340 (-8050 1950);
PAINT GREEN (-8050 1950);
DISPLAY INVISIBLE (-8050 1950);
FORCEPROP 2 LAST CDS_LIB mstr_standard
J 0
(-8375 2075);
DISPLAY 0.808511 (-8375 2075);
DISPLAY INVISIBLE (-8375 2075);
FORCEADD OFFPAGE..1
(-8200 3225);
FORCEPROP 2 LAST $XR0 38 
J 0
(-8421 3225);
DISPLAY 0.638298 (-8421 3225);
PAINT MONO (-8421 3225);
FORCEPROP 2 LAST PATH I10
J 0
(-8400 3275);
DISPLAY 1.021277 (-8400 3275);
DISPLAY INVISIBLE (-8400 3275);
FORCEPROP 1 LAST COMMENT_BODY TRUE
J 0
(-8075 3125);
DISPLAY 0.872340 (-8075 3125);
PAINT GREEN (-8075 3125);
DISPLAY INVISIBLE (-8075 3125);
FORCEPROP 1 LAST OFFPAGE TRUE
J 0
(-7875 3100);
DISPLAY 0.872340 (-7875 3100);
PAINT GREEN (-7875 3100);
DISPLAY INVISIBLE (-7875 3100);
FORCEPROP 2 LAST CDS_LIB mstr_standard
J 0
(-8200 3225);
DISPLAY 0.808511 (-8200 3225);
DISPLAY INVISIBLE (-8200 3225);
FORCEADD TAP..1
(-6075 4325);
FORCEPROP 3 LASTPIN (-6125 4325) SIG_NAME M_B_CPU1_SA_DQ<7>
J 0
(-6115 4335);
DISPLAY 0.659574 (-6115 4335);
PAINT MONO (-6115 4335);
DISPLAY INVISIBLE (-6115 4335);
FORCEPROP 1 LASTPIN (-6125 4325) BN 7
J 0
(-6137 4333);
DISPLAY 0.489362 (-6137 4333);
PAINT GREEN (-6137 4333);
FORCEPROP 2 LAST CDS_LIB mstr_standard
J 0
(-6075 4325);
DISPLAY 0.723404 (-6075 4325);
PAINT MONO (-6075 4325);
DISPLAY INVISIBLE (-6075 4325);
FORCEPROP 1 LAST BODY_TYPE PLUMBING
J 0
(-6075 4375);
DISPLAY 0.872340 (-6075 4375);
PAINT GREEN (-6075 4375);
DISPLAY INVISIBLE (-6075 4375);
FORCEPROP 1 LAST HDL_TAP TRUE
J 0
(-5750 4200);
DISPLAY 0.872340 (-5750 4200);
DISPLAY INVISIBLE (-5750 4200);
FORCEPROP 1 LAST PATH I100
J 0
(-6077 4325);
DISPLAY 0.872340 (-6077 4325);
PAINT GREEN (-6077 4325);
DISPLAY INVISIBLE (-6077 4325);
FORCEADD TAP..1
(-6075 4575);
FORCEPROP 3 LASTPIN (-6125 4575) SIG_NAME M_B_CPU1_SA_DQ<12>
J 0
(-6115 4585);
DISPLAY 0.659574 (-6115 4585);
PAINT MONO (-6115 4585);
DISPLAY INVISIBLE (-6115 4585);
FORCEPROP 1 LASTPIN (-6125 4575) BN 12
J 0
(-6137 4583);
DISPLAY 0.489362 (-6137 4583);
PAINT GREEN (-6137 4583);
FORCEPROP 2 LAST CDS_LIB mstr_standard
J 0
(-6075 4575);
DISPLAY 0.723404 (-6075 4575);
PAINT MONO (-6075 4575);
DISPLAY INVISIBLE (-6075 4575);
FORCEPROP 1 LAST BODY_TYPE PLUMBING
J 0
(-6075 4625);
DISPLAY 0.872340 (-6075 4625);
PAINT GREEN (-6075 4625);
DISPLAY INVISIBLE (-6075 4625);
FORCEPROP 1 LAST HDL_TAP TRUE
J 0
(-5750 4450);
DISPLAY 0.872340 (-5750 4450);
DISPLAY INVISIBLE (-5750 4450);
FORCEPROP 1 LAST PATH I101
J 0
(-6077 4575);
DISPLAY 0.872340 (-6077 4575);
PAINT GREEN (-6077 4575);
DISPLAY INVISIBLE (-6077 4575);
FORCEADD TAP..1
(-6075 4525);
FORCEPROP 3 LASTPIN (-6125 4525) SIG_NAME M_B_CPU1_SA_DQ<11>
J 0
(-6115 4535);
DISPLAY 0.659574 (-6115 4535);
PAINT MONO (-6115 4535);
DISPLAY INVISIBLE (-6115 4535);
FORCEPROP 1 LASTPIN (-6125 4525) BN 11
J 0
(-6137 4533);
DISPLAY 0.489362 (-6137 4533);
PAINT GREEN (-6137 4533);
FORCEPROP 2 LAST CDS_LIB mstr_standard
J 0
(-6075 4525);
DISPLAY 0.723404 (-6075 4525);
PAINT MONO (-6075 4525);
DISPLAY INVISIBLE (-6075 4525);
FORCEPROP 1 LAST BODY_TYPE PLUMBING
J 0
(-6075 4575);
DISPLAY 0.872340 (-6075 4575);
PAINT GREEN (-6075 4575);
DISPLAY INVISIBLE (-6075 4575);
FORCEPROP 1 LAST HDL_TAP TRUE
J 0
(-5750 4400);
DISPLAY 0.872340 (-5750 4400);
DISPLAY INVISIBLE (-5750 4400);
FORCEPROP 1 LAST PATH I102
J 0
(-6077 4525);
DISPLAY 0.872340 (-6077 4525);
PAINT GREEN (-6077 4525);
DISPLAY INVISIBLE (-6077 4525);
FORCEADD TAP..1
(-6075 4475);
FORCEPROP 3 LASTPIN (-6125 4475) SIG_NAME M_B_CPU1_SA_DQ<10>
J 0
(-6115 4485);
DISPLAY 0.659574 (-6115 4485);
PAINT MONO (-6115 4485);
DISPLAY INVISIBLE (-6115 4485);
FORCEPROP 1 LASTPIN (-6125 4475) BN 10
J 0
(-6137 4483);
DISPLAY 0.489362 (-6137 4483);
PAINT GREEN (-6137 4483);
FORCEPROP 2 LAST CDS_LIB mstr_standard
J 0
(-6075 4475);
DISPLAY 0.723404 (-6075 4475);
PAINT MONO (-6075 4475);
DISPLAY INVISIBLE (-6075 4475);
FORCEPROP 1 LAST BODY_TYPE PLUMBING
J 0
(-6075 4525);
DISPLAY 0.872340 (-6075 4525);
PAINT GREEN (-6075 4525);
DISPLAY INVISIBLE (-6075 4525);
FORCEPROP 1 LAST HDL_TAP TRUE
J 0
(-5750 4350);
DISPLAY 0.872340 (-5750 4350);
DISPLAY INVISIBLE (-5750 4350);
FORCEPROP 1 LAST PATH I103
J 0
(-6077 4475);
DISPLAY 0.872340 (-6077 4475);
PAINT GREEN (-6077 4475);
DISPLAY INVISIBLE (-6077 4475);
FORCEADD TAP..1
(-6075 4425);
FORCEPROP 3 LASTPIN (-6125 4425) SIG_NAME M_B_CPU1_SA_DQ<9>
J 0
(-6115 4435);
DISPLAY 0.659574 (-6115 4435);
PAINT MONO (-6115 4435);
DISPLAY INVISIBLE (-6115 4435);
FORCEPROP 1 LASTPIN (-6125 4425) BN 9
J 0
(-6137 4433);
DISPLAY 0.489362 (-6137 4433);
PAINT GREEN (-6137 4433);
FORCEPROP 2 LAST CDS_LIB mstr_standard
J 0
(-6075 4425);
DISPLAY 0.723404 (-6075 4425);
PAINT MONO (-6075 4425);
DISPLAY INVISIBLE (-6075 4425);
FORCEPROP 1 LAST BODY_TYPE PLUMBING
J 0
(-6075 4475);
DISPLAY 0.872340 (-6075 4475);
PAINT GREEN (-6075 4475);
DISPLAY INVISIBLE (-6075 4475);
FORCEPROP 1 LAST HDL_TAP TRUE
J 0
(-5750 4300);
DISPLAY 0.872340 (-5750 4300);
DISPLAY INVISIBLE (-5750 4300);
FORCEPROP 1 LAST PATH I104
J 0
(-6077 4425);
DISPLAY 0.872340 (-6077 4425);
PAINT GREEN (-6077 4425);
DISPLAY INVISIBLE (-6077 4425);
FORCEADD TAP..1
(-6075 4375);
FORCEPROP 3 LASTPIN (-6125 4375) SIG_NAME M_B_CPU1_SA_DQ<8>
J 0
(-6115 4385);
DISPLAY 0.659574 (-6115 4385);
PAINT MONO (-6115 4385);
DISPLAY INVISIBLE (-6115 4385);
FORCEPROP 1 LASTPIN (-6125 4375) BN 8
J 0
(-6137 4383);
DISPLAY 0.489362 (-6137 4383);
PAINT GREEN (-6137 4383);
FORCEPROP 2 LAST CDS_LIB mstr_standard
J 0
(-6075 4375);
DISPLAY 0.723404 (-6075 4375);
PAINT MONO (-6075 4375);
DISPLAY INVISIBLE (-6075 4375);
FORCEPROP 1 LAST BODY_TYPE PLUMBING
J 0
(-6075 4425);
DISPLAY 0.872340 (-6075 4425);
PAINT GREEN (-6075 4425);
DISPLAY INVISIBLE (-6075 4425);
FORCEPROP 1 LAST HDL_TAP TRUE
J 0
(-5750 4250);
DISPLAY 0.872340 (-5750 4250);
DISPLAY INVISIBLE (-5750 4250);
FORCEPROP 1 LAST PATH I105
J 0
(-6077 4375);
DISPLAY 0.872340 (-6077 4375);
PAINT GREEN (-6077 4375);
DISPLAY INVISIBLE (-6077 4375);
FORCEADD TAP..1
(-6075 4825);
FORCEPROP 3 LASTPIN (-6125 4825) SIG_NAME M_B_CPU1_SA_DQ<17>
J 0
(-6115 4835);
DISPLAY 0.659574 (-6115 4835);
PAINT MONO (-6115 4835);
DISPLAY INVISIBLE (-6115 4835);
FORCEPROP 1 LASTPIN (-6125 4825) BN 17
J 0
(-6137 4833);
DISPLAY 0.489362 (-6137 4833);
PAINT GREEN (-6137 4833);
FORCEPROP 2 LAST CDS_LIB mstr_standard
J 0
(-6075 4825);
DISPLAY 0.723404 (-6075 4825);
PAINT MONO (-6075 4825);
DISPLAY INVISIBLE (-6075 4825);
FORCEPROP 1 LAST BODY_TYPE PLUMBING
J 0
(-6075 4875);
DISPLAY 0.872340 (-6075 4875);
PAINT GREEN (-6075 4875);
DISPLAY INVISIBLE (-6075 4875);
FORCEPROP 1 LAST HDL_TAP TRUE
J 0
(-5750 4700);
DISPLAY 0.872340 (-5750 4700);
DISPLAY INVISIBLE (-5750 4700);
FORCEPROP 1 LAST PATH I106
J 0
(-6077 4825);
DISPLAY 0.872340 (-6077 4825);
PAINT GREEN (-6077 4825);
DISPLAY INVISIBLE (-6077 4825);
FORCEADD TAP..1
(-6075 4775);
FORCEPROP 3 LASTPIN (-6125 4775) SIG_NAME M_B_CPU1_SA_DQ<16>
J 0
(-6115 4785);
DISPLAY 0.659574 (-6115 4785);
PAINT MONO (-6115 4785);
DISPLAY INVISIBLE (-6115 4785);
FORCEPROP 1 LASTPIN (-6125 4775) BN 16
J 0
(-6137 4783);
DISPLAY 0.489362 (-6137 4783);
PAINT GREEN (-6137 4783);
FORCEPROP 2 LAST CDS_LIB mstr_standard
J 0
(-6075 4775);
DISPLAY 0.723404 (-6075 4775);
PAINT MONO (-6075 4775);
DISPLAY INVISIBLE (-6075 4775);
FORCEPROP 1 LAST BODY_TYPE PLUMBING
J 0
(-6075 4825);
DISPLAY 0.872340 (-6075 4825);
PAINT GREEN (-6075 4825);
DISPLAY INVISIBLE (-6075 4825);
FORCEPROP 1 LAST HDL_TAP TRUE
J 0
(-5750 4650);
DISPLAY 0.872340 (-5750 4650);
DISPLAY INVISIBLE (-5750 4650);
FORCEPROP 1 LAST PATH I107
J 0
(-6077 4775);
DISPLAY 0.872340 (-6077 4775);
PAINT GREEN (-6077 4775);
DISPLAY INVISIBLE (-6077 4775);
FORCEADD TAP..1
(-6075 4625);
FORCEPROP 3 LASTPIN (-6125 4625) SIG_NAME M_B_CPU1_SA_DQ<13>
J 0
(-6115 4635);
DISPLAY 0.659574 (-6115 4635);
PAINT MONO (-6115 4635);
DISPLAY INVISIBLE (-6115 4635);
FORCEPROP 1 LASTPIN (-6125 4625) BN 13
J 0
(-6137 4633);
DISPLAY 0.489362 (-6137 4633);
PAINT GREEN (-6137 4633);
FORCEPROP 2 LAST CDS_LIB mstr_standard
J 0
(-6075 4625);
DISPLAY 0.723404 (-6075 4625);
PAINT MONO (-6075 4625);
DISPLAY INVISIBLE (-6075 4625);
FORCEPROP 1 LAST BODY_TYPE PLUMBING
J 0
(-6075 4675);
DISPLAY 0.872340 (-6075 4675);
PAINT GREEN (-6075 4675);
DISPLAY INVISIBLE (-6075 4675);
FORCEPROP 1 LAST HDL_TAP TRUE
J 0
(-5750 4500);
DISPLAY 0.872340 (-5750 4500);
DISPLAY INVISIBLE (-5750 4500);
FORCEPROP 1 LAST PATH I108
J 0
(-6077 4625);
DISPLAY 0.872340 (-6077 4625);
PAINT GREEN (-6077 4625);
DISPLAY INVISIBLE (-6077 4625);
FORCEADD TAP..1
(-6075 4725);
FORCEPROP 3 LASTPIN (-6125 4725) SIG_NAME M_B_CPU1_SA_DQ<15>
J 0
(-6115 4735);
DISPLAY 0.659574 (-6115 4735);
PAINT MONO (-6115 4735);
DISPLAY INVISIBLE (-6115 4735);
FORCEPROP 1 LASTPIN (-6125 4725) BN 15
J 0
(-6137 4733);
DISPLAY 0.489362 (-6137 4733);
PAINT GREEN (-6137 4733);
FORCEPROP 2 LAST CDS_LIB mstr_standard
J 0
(-6075 4725);
DISPLAY 0.723404 (-6075 4725);
PAINT MONO (-6075 4725);
DISPLAY INVISIBLE (-6075 4725);
FORCEPROP 1 LAST BODY_TYPE PLUMBING
J 0
(-6075 4775);
DISPLAY 0.872340 (-6075 4775);
PAINT GREEN (-6075 4775);
DISPLAY INVISIBLE (-6075 4775);
FORCEPROP 1 LAST HDL_TAP TRUE
J 0
(-5750 4600);
DISPLAY 0.872340 (-5750 4600);
DISPLAY INVISIBLE (-5750 4600);
FORCEPROP 1 LAST PATH I109
J 0
(-6077 4725);
DISPLAY 0.872340 (-6077 4725);
PAINT GREEN (-6077 4725);
DISPLAY INVISIBLE (-6077 4725);
FORCEADD OFFPAGE..1
(-8375 4675);
FORCEPROP 2 LAST $XR0 38 
J 0
(-8626 4675);
DISPLAY 0.638298 (-8626 4675);
PAINT MONO (-8626 4675);
FORCEPROP 2 LAST PATH I11
J 0
(-8575 4725);
DISPLAY 1.021277 (-8575 4725);
DISPLAY INVISIBLE (-8575 4725);
FORCEPROP 1 LAST COMMENT_BODY TRUE
J 0
(-8250 4575);
DISPLAY 0.872340 (-8250 4575);
PAINT GREEN (-8250 4575);
DISPLAY INVISIBLE (-8250 4575);
FORCEPROP 1 LAST OFFPAGE TRUE
J 0
(-8050 4550);
DISPLAY 0.872340 (-8050 4550);
PAINT GREEN (-8050 4550);
DISPLAY INVISIBLE (-8050 4550);
FORCEPROP 2 LAST CDS_LIB mstr_standard
J 0
(-8375 4675);
DISPLAY 0.808511 (-8375 4675);
DISPLAY INVISIBLE (-8375 4675);
FORCEADD TAP..1
(-6075 4675);
FORCEPROP 3 LASTPIN (-6125 4675) SIG_NAME M_B_CPU1_SA_DQ<14>
J 0
(-6115 4685);
DISPLAY 0.659574 (-6115 4685);
PAINT MONO (-6115 4685);
DISPLAY INVISIBLE (-6115 4685);
FORCEPROP 1 LASTPIN (-6125 4675) BN 14
J 0
(-6137 4683);
DISPLAY 0.489362 (-6137 4683);
PAINT GREEN (-6137 4683);
FORCEPROP 2 LAST CDS_LIB mstr_standard
J 0
(-6075 4675);
DISPLAY 0.723404 (-6075 4675);
PAINT MONO (-6075 4675);
DISPLAY INVISIBLE (-6075 4675);
FORCEPROP 1 LAST BODY_TYPE PLUMBING
J 0
(-6075 4725);
DISPLAY 0.872340 (-6075 4725);
PAINT GREEN (-6075 4725);
DISPLAY INVISIBLE (-6075 4725);
FORCEPROP 1 LAST HDL_TAP TRUE
J 0
(-5750 4550);
DISPLAY 0.872340 (-5750 4550);
DISPLAY INVISIBLE (-5750 4550);
FORCEPROP 1 LAST PATH I110
J 0
(-6077 4675);
DISPLAY 0.872340 (-6077 4675);
PAINT GREEN (-6077 4675);
DISPLAY INVISIBLE (-6077 4675);
FORCEADD TAP..1
(-6075 5025);
FORCEPROP 3 LASTPIN (-6125 5025) SIG_NAME M_B_CPU1_SA_DQ<21>
J 0
(-6115 5035);
DISPLAY 0.659574 (-6115 5035);
PAINT MONO (-6115 5035);
DISPLAY INVISIBLE (-6115 5035);
FORCEPROP 1 LASTPIN (-6125 5025) BN 21
J 0
(-6137 5033);
DISPLAY 0.489362 (-6137 5033);
PAINT GREEN (-6137 5033);
FORCEPROP 2 LAST CDS_LIB mstr_standard
J 0
(-6075 5025);
DISPLAY 0.723404 (-6075 5025);
PAINT MONO (-6075 5025);
DISPLAY INVISIBLE (-6075 5025);
FORCEPROP 1 LAST BODY_TYPE PLUMBING
J 0
(-6075 5075);
DISPLAY 0.872340 (-6075 5075);
PAINT GREEN (-6075 5075);
DISPLAY INVISIBLE (-6075 5075);
FORCEPROP 1 LAST HDL_TAP TRUE
J 0
(-5750 4900);
DISPLAY 0.872340 (-5750 4900);
DISPLAY INVISIBLE (-5750 4900);
FORCEPROP 1 LAST PATH I111
J 0
(-6077 5025);
DISPLAY 0.872340 (-6077 5025);
PAINT GREEN (-6077 5025);
DISPLAY INVISIBLE (-6077 5025);
FORCEADD TAP..1
(-6075 5075);
FORCEPROP 3 LASTPIN (-6125 5075) SIG_NAME M_B_CPU1_SA_DQ<22>
J 0
(-6115 5085);
DISPLAY 0.659574 (-6115 5085);
PAINT MONO (-6115 5085);
DISPLAY INVISIBLE (-6115 5085);
FORCEPROP 1 LASTPIN (-6125 5075) BN 22
J 0
(-6137 5083);
DISPLAY 0.489362 (-6137 5083);
PAINT GREEN (-6137 5083);
FORCEPROP 2 LAST CDS_LIB mstr_standard
J 0
(-6075 5075);
DISPLAY 0.723404 (-6075 5075);
PAINT MONO (-6075 5075);
DISPLAY INVISIBLE (-6075 5075);
FORCEPROP 1 LAST BODY_TYPE PLUMBING
J 0
(-6075 5125);
DISPLAY 0.872340 (-6075 5125);
PAINT GREEN (-6075 5125);
DISPLAY INVISIBLE (-6075 5125);
FORCEPROP 1 LAST HDL_TAP TRUE
J 0
(-5750 4950);
DISPLAY 0.872340 (-5750 4950);
DISPLAY INVISIBLE (-5750 4950);
FORCEPROP 1 LAST PATH I112
J 0
(-6077 5075);
DISPLAY 0.872340 (-6077 5075);
PAINT GREEN (-6077 5075);
DISPLAY INVISIBLE (-6077 5075);
FORCEADD TAP..1
(-6075 4925);
FORCEPROP 3 LASTPIN (-6125 4925) SIG_NAME M_B_CPU1_SA_DQ<19>
J 0
(-6115 4935);
DISPLAY 0.659574 (-6115 4935);
PAINT MONO (-6115 4935);
DISPLAY INVISIBLE (-6115 4935);
FORCEPROP 1 LASTPIN (-6125 4925) BN 19
J 0
(-6137 4933);
DISPLAY 0.489362 (-6137 4933);
PAINT GREEN (-6137 4933);
FORCEPROP 2 LAST CDS_LIB mstr_standard
J 0
(-6075 4925);
DISPLAY 0.723404 (-6075 4925);
PAINT MONO (-6075 4925);
DISPLAY INVISIBLE (-6075 4925);
FORCEPROP 1 LAST BODY_TYPE PLUMBING
J 0
(-6075 4975);
DISPLAY 0.872340 (-6075 4975);
PAINT GREEN (-6075 4975);
DISPLAY INVISIBLE (-6075 4975);
FORCEPROP 1 LAST HDL_TAP TRUE
J 0
(-5750 4800);
DISPLAY 0.872340 (-5750 4800);
DISPLAY INVISIBLE (-5750 4800);
FORCEPROP 1 LAST PATH I113
J 0
(-6077 4925);
DISPLAY 0.872340 (-6077 4925);
PAINT GREEN (-6077 4925);
DISPLAY INVISIBLE (-6077 4925);
FORCEADD TAP..1
(-6075 4975);
FORCEPROP 3 LASTPIN (-6125 4975) SIG_NAME M_B_CPU1_SA_DQ<20>
J 0
(-6115 4985);
DISPLAY 0.659574 (-6115 4985);
PAINT MONO (-6115 4985);
DISPLAY INVISIBLE (-6115 4985);
FORCEPROP 1 LASTPIN (-6125 4975) BN 20
J 0
(-6137 4983);
DISPLAY 0.489362 (-6137 4983);
PAINT GREEN (-6137 4983);
FORCEPROP 2 LAST CDS_LIB mstr_standard
J 0
(-6075 4975);
DISPLAY 0.723404 (-6075 4975);
PAINT MONO (-6075 4975);
DISPLAY INVISIBLE (-6075 4975);
FORCEPROP 1 LAST BODY_TYPE PLUMBING
J 0
(-6075 5025);
DISPLAY 0.872340 (-6075 5025);
PAINT GREEN (-6075 5025);
DISPLAY INVISIBLE (-6075 5025);
FORCEPROP 1 LAST HDL_TAP TRUE
J 0
(-5750 4850);
DISPLAY 0.872340 (-5750 4850);
DISPLAY INVISIBLE (-5750 4850);
FORCEPROP 1 LAST PATH I114
J 0
(-6077 4975);
DISPLAY 0.872340 (-6077 4975);
PAINT GREEN (-6077 4975);
DISPLAY INVISIBLE (-6077 4975);
FORCEADD TAP..1
(-6075 4875);
FORCEPROP 3 LASTPIN (-6125 4875) SIG_NAME M_B_CPU1_SA_DQ<18>
J 0
(-6115 4885);
DISPLAY 0.659574 (-6115 4885);
PAINT MONO (-6115 4885);
DISPLAY INVISIBLE (-6115 4885);
FORCEPROP 1 LASTPIN (-6125 4875) BN 18
J 0
(-6137 4883);
DISPLAY 0.489362 (-6137 4883);
PAINT GREEN (-6137 4883);
FORCEPROP 2 LAST CDS_LIB mstr_standard
J 0
(-6075 4875);
DISPLAY 0.723404 (-6075 4875);
PAINT MONO (-6075 4875);
DISPLAY INVISIBLE (-6075 4875);
FORCEPROP 1 LAST BODY_TYPE PLUMBING
J 0
(-6075 4925);
DISPLAY 0.872340 (-6075 4925);
PAINT GREEN (-6075 4925);
DISPLAY INVISIBLE (-6075 4925);
FORCEPROP 1 LAST HDL_TAP TRUE
J 0
(-5750 4750);
DISPLAY 0.872340 (-5750 4750);
DISPLAY INVISIBLE (-5750 4750);
FORCEPROP 1 LAST PATH I115
J 0
(-6077 4875);
DISPLAY 0.872340 (-6077 4875);
PAINT GREEN (-6077 4875);
DISPLAY INVISIBLE (-6077 4875);
FORCEADD TAP..1
(-6075 5125);
FORCEPROP 3 LASTPIN (-6125 5125) SIG_NAME M_B_CPU1_SA_DQ<23>
J 0
(-6115 5135);
DISPLAY 0.659574 (-6115 5135);
PAINT MONO (-6115 5135);
DISPLAY INVISIBLE (-6115 5135);
FORCEPROP 1 LASTPIN (-6125 5125) BN 23
J 0
(-6137 5133);
DISPLAY 0.489362 (-6137 5133);
PAINT GREEN (-6137 5133);
FORCEPROP 2 LAST CDS_LIB mstr_standard
J 0
(-6075 5125);
DISPLAY 0.723404 (-6075 5125);
PAINT MONO (-6075 5125);
DISPLAY INVISIBLE (-6075 5125);
FORCEPROP 1 LAST BODY_TYPE PLUMBING
J 0
(-6075 5175);
DISPLAY 0.872340 (-6075 5175);
PAINT GREEN (-6075 5175);
DISPLAY INVISIBLE (-6075 5175);
FORCEPROP 1 LAST HDL_TAP TRUE
J 0
(-5750 5000);
DISPLAY 0.872340 (-5750 5000);
DISPLAY INVISIBLE (-5750 5000);
FORCEPROP 1 LAST PATH I116
J 0
(-6077 5125);
DISPLAY 0.872340 (-6077 5125);
PAINT GREEN (-6077 5125);
DISPLAY INVISIBLE (-6077 5125);
FORCEADD TAP..1
(-6075 5175);
FORCEPROP 3 LASTPIN (-6125 5175) SIG_NAME M_B_CPU1_SA_DQ<24>
J 0
(-6115 5185);
DISPLAY 0.659574 (-6115 5185);
PAINT MONO (-6115 5185);
DISPLAY INVISIBLE (-6115 5185);
FORCEPROP 1 LASTPIN (-6125 5175) BN 24
J 0
(-6137 5183);
DISPLAY 0.489362 (-6137 5183);
PAINT GREEN (-6137 5183);
FORCEPROP 2 LAST CDS_LIB mstr_standard
J 0
(-6075 5175);
DISPLAY 0.723404 (-6075 5175);
PAINT MONO (-6075 5175);
DISPLAY INVISIBLE (-6075 5175);
FORCEPROP 1 LAST BODY_TYPE PLUMBING
J 0
(-6075 5225);
DISPLAY 0.872340 (-6075 5225);
PAINT GREEN (-6075 5225);
DISPLAY INVISIBLE (-6075 5225);
FORCEPROP 1 LAST HDL_TAP TRUE
J 0
(-5750 5050);
DISPLAY 0.872340 (-5750 5050);
DISPLAY INVISIBLE (-5750 5050);
FORCEPROP 1 LAST PATH I117
J 0
(-6077 5175);
DISPLAY 0.872340 (-6077 5175);
PAINT GREEN (-6077 5175);
DISPLAY INVISIBLE (-6077 5175);
FORCEADD TAP..1
(-6075 5225);
FORCEPROP 3 LASTPIN (-6125 5225) SIG_NAME M_B_CPU1_SA_DQ<25>
J 0
(-6115 5235);
DISPLAY 0.659574 (-6115 5235);
PAINT MONO (-6115 5235);
DISPLAY INVISIBLE (-6115 5235);
FORCEPROP 1 LASTPIN (-6125 5225) BN 25
J 0
(-6137 5233);
DISPLAY 0.489362 (-6137 5233);
PAINT GREEN (-6137 5233);
FORCEPROP 2 LAST CDS_LIB mstr_standard
J 0
(-6075 5225);
DISPLAY 0.723404 (-6075 5225);
PAINT MONO (-6075 5225);
DISPLAY INVISIBLE (-6075 5225);
FORCEPROP 1 LAST BODY_TYPE PLUMBING
J 0
(-6075 5275);
DISPLAY 0.872340 (-6075 5275);
PAINT GREEN (-6075 5275);
DISPLAY INVISIBLE (-6075 5275);
FORCEPROP 1 LAST HDL_TAP TRUE
J 0
(-5750 5100);
DISPLAY 0.872340 (-5750 5100);
DISPLAY INVISIBLE (-5750 5100);
FORCEPROP 1 LAST PATH I118
J 0
(-6077 5225);
DISPLAY 0.872340 (-6077 5225);
PAINT GREEN (-6077 5225);
DISPLAY INVISIBLE (-6077 5225);
FORCEADD TAP..1
(-6075 5375);
FORCEPROP 3 LASTPIN (-6125 5375) SIG_NAME M_B_CPU1_SA_DQ<28>
J 0
(-6115 5385);
DISPLAY 0.659574 (-6115 5385);
PAINT MONO (-6115 5385);
DISPLAY INVISIBLE (-6115 5385);
FORCEPROP 1 LASTPIN (-6125 5375) BN 28
J 0
(-6137 5383);
DISPLAY 0.489362 (-6137 5383);
PAINT GREEN (-6137 5383);
FORCEPROP 2 LAST CDS_LIB mstr_standard
J 0
(-6075 5375);
DISPLAY 0.723404 (-6075 5375);
PAINT MONO (-6075 5375);
DISPLAY INVISIBLE (-6075 5375);
FORCEPROP 1 LAST BODY_TYPE PLUMBING
J 0
(-6075 5425);
DISPLAY 0.872340 (-6075 5425);
PAINT GREEN (-6075 5425);
DISPLAY INVISIBLE (-6075 5425);
FORCEPROP 1 LAST HDL_TAP TRUE
J 0
(-5750 5250);
DISPLAY 0.872340 (-5750 5250);
DISPLAY INVISIBLE (-5750 5250);
FORCEPROP 1 LAST PATH I119
J 0
(-6077 5375);
DISPLAY 0.872340 (-6077 5375);
PAINT GREEN (-6077 5375);
DISPLAY INVISIBLE (-6077 5375);
FORCEADD OFFPAGE..1
(-8375 4725);
FORCEPROP 2 LAST $XR0 38 
J 0
(-8626 4725);
DISPLAY 0.638298 (-8626 4725);
PAINT MONO (-8626 4725);
FORCEPROP 2 LAST PATH I12
J 0
(-8575 4775);
DISPLAY 1.021277 (-8575 4775);
DISPLAY INVISIBLE (-8575 4775);
FORCEPROP 1 LAST COMMENT_BODY TRUE
J 0
(-8250 4625);
DISPLAY 0.872340 (-8250 4625);
PAINT GREEN (-8250 4625);
DISPLAY INVISIBLE (-8250 4625);
FORCEPROP 1 LAST OFFPAGE TRUE
J 0
(-8050 4600);
DISPLAY 0.872340 (-8050 4600);
PAINT GREEN (-8050 4600);
DISPLAY INVISIBLE (-8050 4600);
FORCEPROP 2 LAST CDS_LIB mstr_standard
J 0
(-8375 4725);
DISPLAY 0.723404 (-8375 4725);
PAINT MONO (-8375 4725);
DISPLAY INVISIBLE (-8375 4725);
FORCEADD TAP..1
(-6075 5325);
FORCEPROP 3 LASTPIN (-6125 5325) SIG_NAME M_B_CPU1_SA_DQ<27>
J 0
(-6115 5335);
DISPLAY 0.659574 (-6115 5335);
PAINT MONO (-6115 5335);
DISPLAY INVISIBLE (-6115 5335);
FORCEPROP 1 LASTPIN (-6125 5325) BN 27
J 0
(-6137 5333);
DISPLAY 0.489362 (-6137 5333);
PAINT GREEN (-6137 5333);
FORCEPROP 2 LAST CDS_LIB mstr_standard
J 0
(-6075 5325);
DISPLAY 0.723404 (-6075 5325);
PAINT MONO (-6075 5325);
DISPLAY INVISIBLE (-6075 5325);
FORCEPROP 1 LAST BODY_TYPE PLUMBING
J 0
(-6075 5375);
DISPLAY 0.872340 (-6075 5375);
PAINT GREEN (-6075 5375);
DISPLAY INVISIBLE (-6075 5375);
FORCEPROP 1 LAST HDL_TAP TRUE
J 0
(-5750 5200);
DISPLAY 0.872340 (-5750 5200);
DISPLAY INVISIBLE (-5750 5200);
FORCEPROP 1 LAST PATH I120
J 0
(-6077 5325);
DISPLAY 0.872340 (-6077 5325);
PAINT GREEN (-6077 5325);
DISPLAY INVISIBLE (-6077 5325);
FORCEADD TAP..1
(-6075 5275);
FORCEPROP 3 LASTPIN (-6125 5275) SIG_NAME M_B_CPU1_SA_DQ<26>
J 0
(-6115 5285);
DISPLAY 0.659574 (-6115 5285);
PAINT MONO (-6115 5285);
DISPLAY INVISIBLE (-6115 5285);
FORCEPROP 1 LASTPIN (-6125 5275) BN 26
J 0
(-6137 5283);
DISPLAY 0.489362 (-6137 5283);
PAINT GREEN (-6137 5283);
FORCEPROP 2 LAST CDS_LIB mstr_standard
J 0
(-6075 5275);
DISPLAY 0.723404 (-6075 5275);
PAINT MONO (-6075 5275);
DISPLAY INVISIBLE (-6075 5275);
FORCEPROP 1 LAST BODY_TYPE PLUMBING
J 0
(-6075 5325);
DISPLAY 0.872340 (-6075 5325);
PAINT GREEN (-6075 5325);
DISPLAY INVISIBLE (-6075 5325);
FORCEPROP 1 LAST HDL_TAP TRUE
J 0
(-5750 5150);
DISPLAY 0.872340 (-5750 5150);
DISPLAY INVISIBLE (-5750 5150);
FORCEPROP 1 LAST PATH I121
J 0
(-6077 5275);
DISPLAY 0.872340 (-6077 5275);
PAINT GREEN (-6077 5275);
DISPLAY INVISIBLE (-6077 5275);
FORCEADD TAP..1
(-6075 5475);
FORCEPROP 3 LASTPIN (-6125 5475) SIG_NAME M_B_CPU1_SA_DQ<30>
J 0
(-6115 5485);
DISPLAY 0.659574 (-6115 5485);
PAINT MONO (-6115 5485);
DISPLAY INVISIBLE (-6115 5485);
FORCEPROP 1 LASTPIN (-6125 5475) BN 30
J 0
(-6137 5483);
DISPLAY 0.489362 (-6137 5483);
PAINT GREEN (-6137 5483);
FORCEPROP 2 LAST CDS_LIB mstr_standard
J 0
(-6075 5475);
DISPLAY 0.723404 (-6075 5475);
PAINT MONO (-6075 5475);
DISPLAY INVISIBLE (-6075 5475);
FORCEPROP 1 LAST BODY_TYPE PLUMBING
J 0
(-6075 5525);
DISPLAY 0.872340 (-6075 5525);
PAINT GREEN (-6075 5525);
DISPLAY INVISIBLE (-6075 5525);
FORCEPROP 1 LAST HDL_TAP TRUE
J 0
(-5750 5350);
DISPLAY 0.872340 (-5750 5350);
DISPLAY INVISIBLE (-5750 5350);
FORCEPROP 1 LAST PATH I122
J 0
(-6077 5475);
DISPLAY 0.872340 (-6077 5475);
PAINT GREEN (-6077 5475);
DISPLAY INVISIBLE (-6077 5475);
FORCEADD TAP..1
(-6075 5425);
FORCEPROP 3 LASTPIN (-6125 5425) SIG_NAME M_B_CPU1_SA_DQ<29>
J 0
(-6115 5435);
DISPLAY 0.659574 (-6115 5435);
PAINT MONO (-6115 5435);
DISPLAY INVISIBLE (-6115 5435);
FORCEPROP 1 LASTPIN (-6125 5425) BN 29
J 0
(-6137 5433);
DISPLAY 0.489362 (-6137 5433);
PAINT GREEN (-6137 5433);
FORCEPROP 2 LAST CDS_LIB mstr_standard
J 0
(-6075 5425);
DISPLAY 0.723404 (-6075 5425);
PAINT MONO (-6075 5425);
DISPLAY INVISIBLE (-6075 5425);
FORCEPROP 1 LAST BODY_TYPE PLUMBING
J 0
(-6075 5475);
DISPLAY 0.872340 (-6075 5475);
PAINT GREEN (-6075 5475);
DISPLAY INVISIBLE (-6075 5475);
FORCEPROP 1 LAST HDL_TAP TRUE
J 0
(-5750 5300);
DISPLAY 0.872340 (-5750 5300);
DISPLAY INVISIBLE (-5750 5300);
FORCEPROP 1 LAST PATH I123
J 0
(-6077 5425);
DISPLAY 0.872340 (-6077 5425);
PAINT GREEN (-6077 5425);
DISPLAY INVISIBLE (-6077 5425);
FORCEADD TAP..1
(-6075 5525);
FORCEPROP 3 LASTPIN (-6125 5525) SIG_NAME M_B_CPU1_SA_DQ<31>
J 0
(-6115 5535);
DISPLAY 0.659574 (-6115 5535);
PAINT MONO (-6115 5535);
DISPLAY INVISIBLE (-6115 5535);
FORCEPROP 1 LASTPIN (-6125 5525) BN 31
J 0
(-6137 5533);
DISPLAY 0.489362 (-6137 5533);
PAINT GREEN (-6137 5533);
FORCEPROP 2 LAST CDS_LIB mstr_standard
J 0
(-6075 5525);
DISPLAY 0.723404 (-6075 5525);
PAINT MONO (-6075 5525);
DISPLAY INVISIBLE (-6075 5525);
FORCEPROP 1 LAST BODY_TYPE PLUMBING
J 0
(-6075 5575);
DISPLAY 0.872340 (-6075 5575);
PAINT GREEN (-6075 5575);
DISPLAY INVISIBLE (-6075 5575);
FORCEPROP 1 LAST HDL_TAP TRUE
J 0
(-5750 5400);
DISPLAY 0.872340 (-5750 5400);
DISPLAY INVISIBLE (-5750 5400);
FORCEPROP 1 LAST PATH I124
J 0
(-6077 5525);
DISPLAY 0.872340 (-6077 5525);
PAINT GREEN (-6077 5525);
DISPLAY INVISIBLE (-6077 5525);
FORCEADD OFFPAGE..3
(-5325 5575);
FORCEPROP 2 LAST $XR0 38 
J 0
(-5111 5575);
DISPLAY 0.638298 (-5111 5575);
PAINT MONO (-5111 5575);
FORCEPROP 2 LAST PATH I125
J 0
(-5100 5625);
DISPLAY 1.021277 (-5100 5625);
DISPLAY INVISIBLE (-5100 5625);
FORCEPROP 1 LAST COMMENT_BODY TRUE
J 0
(-5375 5475);
DISPLAY 0.872340 (-5375 5475);
PAINT GREEN (-5375 5475);
DISPLAY INVISIBLE (-5375 5475);
FORCEPROP 1 LAST OFFPAGE TRUE
J 0
(-5000 5450);
DISPLAY 0.872340 (-5000 5450);
PAINT GREEN (-5000 5450);
DISPLAY INVISIBLE (-5000 5450);
FORCEPROP 2 LAST CDS_LIB mstr_standard
J 0
(-5325 5575);
DISPLAY 0.723404 (-5325 5575);
PAINT MONO (-5325 5575);
DISPLAY INVISIBLE (-5325 5575);
FORCEADD GND..1
(-6475 1225);
FORCEPROP 3 LASTPIN (-6475 1275) SIG_NAME GND\g
J 0
(-6465 1285);
DISPLAY 0.659574 (-6465 1285);
PAINT MONO (-6465 1285);
DISPLAY INVISIBLE (-6465 1285);
FORCEPROP 2 LAST CDS_LIB mstr_symbols
J 0
(-6475 1225);
DISPLAY 0.808511 (-6475 1225);
DISPLAY INVISIBLE (-6475 1225);
FORCEPROP 1 LAST SIZE 1B
J 0
(-6400 1175);
DISPLAY 0.851064 (-6400 1175);
PAINT GREEN (-6400 1175);
DISPLAY INVISIBLE (-6400 1175);
FORCEPROP 2 LAST BOM_COST MEM
J 0
(-6575 1300);
DISPLAY 0.808511 (-6575 1300);
DISPLAY INVISIBLE (-6575 1300);
FORCEPROP 1 LAST BODY_TYPE PLUMBING
J 0
(-6520 1182);
DISPLAY 0.340426 (-6520 1182);
PAINT GREEN (-6520 1182);
DISPLAY INVISIBLE (-6520 1182);
FORCEPROP 1 LAST PATH I126
J 0
(-6400 1225);
DISPLAY 0.872340 (-6400 1225);
PAINT AQUA (-6400 1225);
DISPLAY INVISIBLE (-6400 1225);
FORCEPROP 1 LAST VOLTAGE 0.0
J 0
(-6520 1182);
DISPLAY 0.723404 (-6520 1182);
PAINT SKYBLUE (-6520 1182);
DISPLAY INVISIBLE (-6520 1182);
FORCEPROP 1 LAST HDL_POWER GND
J 0
(-6475 1375);
DISPLAY 0.851064 (-6475 1375);
PAINT GREEN (-6475 1375);
DISPLAY INVISIBLE (-6475 1375);
FORCEADD Q_RES..2
(-6475 1450);
FORCEPROP 1 LAST LOCATION R770
J 0
(-6430 1575);
DISPLAY 0.489362 (-6430 1575);
PAINT SKYBLUE (-6430 1575);
FORCEPROP 0 LAST $SEC 1
J 0
(-6425 1625);
DISPLAY 0.680851 (-6425 1625);
PAINT MONO (-6425 1625);
DISPLAY INVISIBLE (-6425 1625);
FORCEPROP 0 LAST CDS_SEC 1
J 0
(-6425 1625);
DISPLAY 1.021277 (-6425 1625);
DISPLAY INVISIBLE (-6425 1625);
FORCEPROP 1 LASTPIN (-6475 1550) $PN 1
J 0
(-6470 1512);
DISPLAY 0.489362 (-6470 1512);
PAINT MONO (-6470 1512);
FORCEPROP 1 LASTPIN (-6475 1350) $PN 2
J 0
(-6470 1360);
DISPLAY 0.489362 (-6470 1360);
PAINT MONO (-6470 1360);
FORCEPROP 1 LAST WATTAGE 1/16W
J 0
(-6435 1425);
DISPLAY 0.489362 (-6435 1425);
PAINT SKYBLUE (-6435 1425);
FORCEPROP 1 LAST MATERIAL CHIP
J 0
(-6435 1375);
DISPLAY 0.489362 (-6435 1375);
PAINT SKYBLUE (-6435 1375);
FORCEPROP 1 LAST TOLERANCE 1%
J 0
(-6430 1475);
DISPLAY 0.489362 (-6430 1475);
PAINT SKYBLUE (-6430 1475);
FORCEPROP 1 LAST VALUE 15.4K
J 0
(-6430 1525);
DISPLAY 0.489362 (-6430 1525);
PAINT SKYBLUE (-6430 1525);
FORCEPROP 1 LAST PART_NUMBER CS31542FB02
J 0
(-6435 1325);
DISPLAY 0.489362 (-6435 1325);
PAINT SKYBLUE (-6435 1325);
FORCEPROP 1 LAST PACK_TYPE 0402LF
J 0
(-6435 1275);
DISPLAY 0.489362 (-6435 1275);
PAINT SKYBLUE (-6435 1275);
FORCEPROP 2 LAST CDS_LIB pure_quanta
J 0
(-6475 1450);
DISPLAY INVISIBLE (-6475 1450);
FORCEPROP 1 LAST PATH I127
J 0
(-6425 1625);
DISPLAY 0.978723 (-6425 1625);
PAINT WHITE (-6425 1625);
DISPLAY INVISIBLE (-6425 1625);
FORCEADD GND..1
(-2175 1725);
FORCEPROP 3 LASTPIN (-2175 1775) SIG_NAME GND\g
J 0
(-2165 1785);
DISPLAY 0.659574 (-2165 1785);
PAINT MONO (-2165 1785);
DISPLAY INVISIBLE (-2165 1785);
FORCEPROP 1 LAST SIZE 1B
J 0
(-2100 1675);
DISPLAY 0.851064 (-2100 1675);
PAINT GREEN (-2100 1675);
DISPLAY INVISIBLE (-2100 1675);
FORCEPROP 2 LAST CDS_LIB mstr_symbols
J 0
(-2175 1725);
DISPLAY 0.723404 (-2175 1725);
DISPLAY INVISIBLE (-2175 1725);
FORCEPROP 1 LAST BODY_TYPE PLUMBING
J 0
(-2220 1682);
DISPLAY 0.340426 (-2220 1682);
PAINT GREEN (-2220 1682);
DISPLAY INVISIBLE (-2220 1682);
FORCEPROP 1 LAST PATH I128
J 0
(-2100 1725);
DISPLAY 0.872340 (-2100 1725);
PAINT AQUA (-2100 1725);
DISPLAY INVISIBLE (-2100 1725);
FORCEPROP 1 LAST VOLTAGE 0.0
J 0
(-2220 1682);
DISPLAY 0.723404 (-2220 1682);
PAINT SKYBLUE (-2220 1682);
DISPLAY INVISIBLE (-2220 1682);
FORCEPROP 1 LAST HDL_POWER GND
J 0
(-2175 1875);
DISPLAY 0.851064 (-2175 1875);
PAINT GREEN (-2175 1875);
DISPLAY INVISIBLE (-2175 1875);
FORCEADD OFFPAGE..5
(-7250 1625);
FORCEPROP 2 LAST $XR0 98 
J 0
(-7504 1625);
DISPLAY 0.638298 (-7504 1625);
PAINT MONO (-7504 1625);
FORCEPROP 2 LAST PATH I129
J 0
(-7500 1675);
DISPLAY 1.021277 (-7500 1675);
DISPLAY INVISIBLE (-7500 1675);
FORCEPROP 1 LAST COMMENT_BODY TRUE
J 0
(-7150 1550);
DISPLAY 0.872340 (-7150 1550);
PAINT GREEN (-7150 1550);
DISPLAY INVISIBLE (-7150 1550);
FORCEPROP 1 LAST OFFPAGE TRUE
J 0
(-6925 1500);
DISPLAY 0.872340 (-6925 1500);
PAINT GREEN (-6925 1500);
DISPLAY INVISIBLE (-6925 1500);
FORCEPROP 2 LAST CDS_LIB mstr_standard
J 0
(-7250 1625);
DISPLAY 0.808511 (-7250 1625);
DISPLAY INVISIBLE (-7250 1625);
FORCEPROP 2 LAST BOM_COST MEM
J 0
(-7325 1700);
DISPLAY 0.808511 (-7325 1700);
DISPLAY INVISIBLE (-7325 1700);
FORCEADD OFFPAGE..1
(-8375 4575);
FORCEPROP 2 LAST $XR0 38 
J 0
(-8626 4575);
DISPLAY 0.638298 (-8626 4575);
PAINT MONO (-8626 4575);
FORCEPROP 2 LAST PATH I13
J 0
(-8575 4625);
DISPLAY 1.021277 (-8575 4625);
DISPLAY INVISIBLE (-8575 4625);
FORCEPROP 1 LAST COMMENT_BODY TRUE
J 0
(-8250 4475);
DISPLAY 0.872340 (-8250 4475);
PAINT GREEN (-8250 4475);
DISPLAY INVISIBLE (-8250 4475);
FORCEPROP 1 LAST OFFPAGE TRUE
J 0
(-8050 4450);
DISPLAY 0.872340 (-8050 4450);
PAINT GREEN (-8050 4450);
DISPLAY INVISIBLE (-8050 4450);
FORCEPROP 2 LAST CDS_LIB mstr_standard
J 0
(-8375 4575);
DISPLAY 0.723404 (-8375 4575);
PAINT MONO (-8375 4575);
DISPLAY INVISIBLE (-8375 4575);
FORCEADD OFFPAGE..1
(-8375 4525);
FORCEPROP 2 LAST $XR0 38 
J 0
(-8626 4525);
DISPLAY 0.638298 (-8626 4525);
PAINT MONO (-8626 4525);
FORCEPROP 2 LAST PATH I14
J 0
(-8575 4575);
DISPLAY 1.021277 (-8575 4575);
DISPLAY INVISIBLE (-8575 4575);
FORCEPROP 1 LAST COMMENT_BODY TRUE
J 0
(-8250 4425);
DISPLAY 0.872340 (-8250 4425);
PAINT GREEN (-8250 4425);
DISPLAY INVISIBLE (-8250 4425);
FORCEPROP 1 LAST OFFPAGE TRUE
J 0
(-8050 4400);
DISPLAY 0.872340 (-8050 4400);
PAINT GREEN (-8050 4400);
DISPLAY INVISIBLE (-8050 4400);
FORCEPROP 2 LAST CDS_LIB mstr_standard
J 0
(-8375 4525);
DISPLAY 0.808511 (-8375 4525);
DISPLAY INVISIBLE (-8375 4525);
FORCEADD OFFPAGE..1
(-8375 4425);
FORCEPROP 2 LAST $XR0 38 
J 0
(-8626 4425);
DISPLAY 0.638298 (-8626 4425);
PAINT MONO (-8626 4425);
FORCEPROP 2 LAST PATH I15
J 0
(-8575 4475);
DISPLAY 1.021277 (-8575 4475);
DISPLAY INVISIBLE (-8575 4475);
FORCEPROP 1 LAST COMMENT_BODY TRUE
J 0
(-8250 4325);
DISPLAY 0.872340 (-8250 4325);
PAINT GREEN (-8250 4325);
DISPLAY INVISIBLE (-8250 4325);
FORCEPROP 1 LAST OFFPAGE TRUE
J 0
(-8050 4300);
DISPLAY 0.872340 (-8050 4300);
PAINT GREEN (-8050 4300);
DISPLAY INVISIBLE (-8050 4300);
FORCEPROP 2 LAST CDS_LIB mstr_standard
J 0
(-8375 4425);
DISPLAY 0.723404 (-8375 4425);
PAINT MONO (-8375 4425);
DISPLAY INVISIBLE (-8375 4425);
FORCEADD OFFPAGE..1
(-8375 4375);
FORCEPROP 2 LAST $XR0 38 
J 0
(-8626 4375);
DISPLAY 0.638298 (-8626 4375);
PAINT MONO (-8626 4375);
FORCEPROP 2 LAST PATH I16
J 0
(-8575 4425);
DISPLAY 1.021277 (-8575 4425);
DISPLAY INVISIBLE (-8575 4425);
FORCEPROP 1 LAST COMMENT_BODY TRUE
J 0
(-8250 4275);
DISPLAY 0.872340 (-8250 4275);
PAINT GREEN (-8250 4275);
DISPLAY INVISIBLE (-8250 4275);
FORCEPROP 1 LAST OFFPAGE TRUE
J 0
(-8050 4250);
DISPLAY 0.872340 (-8050 4250);
PAINT GREEN (-8050 4250);
DISPLAY INVISIBLE (-8050 4250);
FORCEPROP 2 LAST CDS_LIB mstr_standard
J 0
(-8375 4375);
DISPLAY 0.808511 (-8375 4375);
DISPLAY INVISIBLE (-8375 4375);
FORCEADD SCONN288_DDR506112002KQ..3
(-1275 3475);
FORCEPROP 1 LAST LOCATION J26
J 0
(-1725 5450);
DISPLAY 0.468085 (-1725 5450);
PAINT SKYBLUE (-1725 5450);
FORCEPROP 0 LAST $SEC 3
J 0
(-1725 5600);
DISPLAY 0.680851 (-1725 5600);
PAINT MONO (-1725 5600);
DISPLAY INVISIBLE (-1725 5600);
FORCEPROP 2 LAST CDS_SEC 3
J 0
(-1725 5600);
DISPLAY 1.021277 (-1725 5600);
DISPLAY INVISIBLE (-1725 5600);
FORCEPROP 0 LASTPIN (-675 1875) $PN G1
J 0
(-665 1885);
DISPLAY 0.680851 (-665 1885);
PAINT MONO (-665 1885);
FORCEPROP 0 LASTPIN (-675 1825) $PN G2
J 0
(-665 1835);
DISPLAY 0.680851 (-665 1835);
PAINT MONO (-665 1835);
FORCEPROP 0 LASTPIN (-675 1775) $PN G3
J 0
(-665 1785);
DISPLAY 0.680851 (-665 1785);
PAINT MONO (-665 1785);
FORCEPROP 0 LASTPIN (-1875 5025) $PN 1
J 2
(-1885 5035);
DISPLAY 0.680851 (-1885 5035);
PAINT MONO (-1885 5035);
FORCEPROP 0 LASTPIN (-1875 5075) $PN 145
J 2
(-1885 5085);
DISPLAY 0.680851 (-1885 5085);
PAINT MONO (-1885 5085);
FORCEPROP 0 LASTPIN (-1875 5125) $PN 146
J 2
(-1885 5135);
DISPLAY 0.680851 (-1885 5135);
PAINT MONO (-1885 5135);
FORCEPROP 0 LASTPIN (-675 1975) $PN 6
J 0
(-665 1985);
DISPLAY 0.680851 (-665 1985);
PAINT MONO (-665 1985);
FORCEPROP 0 LASTPIN (-675 2025) $PN 8
J 0
(-665 2035);
DISPLAY 0.680851 (-665 2035);
PAINT MONO (-665 2035);
FORCEPROP 0 LASTPIN (-675 2075) $PN 10
J 0
(-665 2085);
DISPLAY 0.680851 (-665 2085);
PAINT MONO (-665 2085);
FORCEPROP 0 LASTPIN (-675 2125) $PN 13
J 0
(-665 2135);
DISPLAY 0.680851 (-665 2135);
PAINT MONO (-665 2135);
FORCEPROP 0 LASTPIN (-675 2175) $PN 15
J 0
(-665 2185);
DISPLAY 0.680851 (-665 2185);
PAINT MONO (-665 2185);
FORCEPROP 0 LASTPIN (-675 2225) $PN 17
J 0
(-665 2235);
DISPLAY 0.680851 (-665 2235);
PAINT MONO (-665 2235);
FORCEPROP 0 LASTPIN (-675 2275) $PN 19
J 0
(-665 2285);
DISPLAY 0.680851 (-665 2285);
PAINT MONO (-665 2285);
FORCEPROP 0 LASTPIN (-675 2325) $PN 21
J 0
(-665 2335);
DISPLAY 0.680851 (-665 2335);
PAINT MONO (-665 2335);
FORCEPROP 0 LASTPIN (-675 2375) $PN 24
J 0
(-665 2385);
DISPLAY 0.680851 (-665 2385);
PAINT MONO (-665 2385);
FORCEPROP 0 LASTPIN (-675 2425) $PN 26
J 0
(-665 2435);
DISPLAY 0.680851 (-665 2435);
PAINT MONO (-665 2435);
FORCEPROP 0 LASTPIN (-675 2475) $PN 28
J 0
(-665 2485);
DISPLAY 0.680851 (-665 2485);
PAINT MONO (-665 2485);
FORCEPROP 0 LASTPIN (-675 2525) $PN 30
J 0
(-665 2535);
DISPLAY 0.680851 (-665 2535);
PAINT MONO (-665 2535);
FORCEPROP 0 LASTPIN (-675 2575) $PN 32
J 0
(-665 2585);
DISPLAY 0.680851 (-665 2585);
PAINT MONO (-665 2585);
FORCEPROP 0 LASTPIN (-675 2625) $PN 35
J 0
(-665 2635);
DISPLAY 0.680851 (-665 2635);
PAINT MONO (-665 2635);
FORCEPROP 0 LASTPIN (-675 2675) $PN 37
J 0
(-665 2685);
DISPLAY 0.680851 (-665 2685);
PAINT MONO (-665 2685);
FORCEPROP 0 LASTPIN (-675 2725) $PN 39
J 0
(-665 2735);
DISPLAY 0.680851 (-665 2735);
PAINT MONO (-665 2735);
FORCEPROP 0 LASTPIN (-675 2775) $PN 41
J 0
(-665 2785);
DISPLAY 0.680851 (-665 2785);
PAINT MONO (-665 2785);
FORCEPROP 0 LASTPIN (-675 2825) $PN 43
J 0
(-665 2835);
DISPLAY 0.680851 (-665 2835);
PAINT MONO (-665 2835);
FORCEPROP 0 LASTPIN (-675 2875) $PN 46
J 0
(-665 2885);
DISPLAY 0.680851 (-665 2885);
PAINT MONO (-665 2885);
FORCEPROP 0 LASTPIN (-675 2925) $PN 48
J 0
(-665 2935);
DISPLAY 0.680851 (-665 2935);
PAINT MONO (-665 2935);
FORCEPROP 0 LASTPIN (-675 2975) $PN 50
J 0
(-665 2985);
DISPLAY 0.680851 (-665 2985);
PAINT MONO (-665 2985);
FORCEPROP 0 LASTPIN (-675 3025) $PN 52
J 0
(-665 3035);
DISPLAY 0.680851 (-665 3035);
PAINT MONO (-665 3035);
FORCEPROP 0 LASTPIN (-675 3075) $PN 54
J 0
(-665 3085);
DISPLAY 0.680851 (-665 3085);
PAINT MONO (-665 3085);
FORCEPROP 0 LASTPIN (-675 3125) $PN 57
J 0
(-665 3135);
DISPLAY 0.680851 (-665 3135);
PAINT MONO (-665 3135);
FORCEPROP 0 LASTPIN (-675 3175) $PN 59
J 0
(-665 3185);
DISPLAY 0.680851 (-665 3185);
PAINT MONO (-665 3185);
FORCEPROP 0 LASTPIN (-675 3225) $PN 61
J 0
(-665 3235);
DISPLAY 0.680851 (-665 3235);
PAINT MONO (-665 3235);
FORCEPROP 0 LASTPIN (-675 3275) $PN 63
J 0
(-665 3285);
DISPLAY 0.680851 (-665 3285);
PAINT MONO (-665 3285);
FORCEPROP 0 LASTPIN (-675 3325) $PN 65
J 0
(-665 3335);
DISPLAY 0.680851 (-665 3335);
PAINT MONO (-665 3335);
FORCEPROP 0 LASTPIN (-675 3375) $PN 67
J 0
(-665 3385);
DISPLAY 0.680851 (-665 3385);
PAINT MONO (-665 3385);
FORCEPROP 0 LASTPIN (-675 3425) $PN 69
J 0
(-665 3435);
DISPLAY 0.680851 (-665 3435);
PAINT MONO (-665 3435);
FORCEPROP 0 LASTPIN (-675 3475) $PN 71
J 0
(-665 3485);
DISPLAY 0.680851 (-665 3485);
PAINT MONO (-665 3485);
FORCEPROP 0 LASTPIN (-675 3525) $PN 73
J 0
(-665 3535);
DISPLAY 0.680851 (-665 3535);
PAINT MONO (-665 3535);
FORCEPROP 0 LASTPIN (-675 3575) $PN 75
J 0
(-665 3585);
DISPLAY 0.680851 (-665 3585);
PAINT MONO (-665 3585);
FORCEPROP 0 LASTPIN (-675 3625) $PN 77
J 0
(-665 3635);
DISPLAY 0.680851 (-665 3635);
PAINT MONO (-665 3635);
FORCEPROP 0 LASTPIN (-675 3675) $PN 79
J 0
(-665 3685);
DISPLAY 0.680851 (-665 3685);
PAINT MONO (-665 3685);
FORCEPROP 0 LASTPIN (-675 3725) $PN 81
J 0
(-665 3735);
DISPLAY 0.680851 (-665 3735);
PAINT MONO (-665 3735);
FORCEPROP 0 LASTPIN (-675 3775) $PN 83
J 0
(-665 3785);
DISPLAY 0.680851 (-665 3785);
PAINT MONO (-665 3785);
FORCEPROP 0 LASTPIN (-675 3825) $PN 85
J 0
(-665 3835);
DISPLAY 0.680851 (-665 3835);
PAINT MONO (-665 3835);
FORCEPROP 0 LASTPIN (-675 3875) $PN 88
J 0
(-665 3885);
DISPLAY 0.680851 (-665 3885);
PAINT MONO (-665 3885);
FORCEPROP 0 LASTPIN (-675 3925) $PN 90
J 0
(-665 3935);
DISPLAY 0.680851 (-665 3935);
PAINT MONO (-665 3935);
FORCEPROP 0 LASTPIN (-675 3975) $PN 92
J 0
(-665 3985);
DISPLAY 0.680851 (-665 3985);
PAINT MONO (-665 3985);
FORCEPROP 0 LASTPIN (-675 4025) $PN 95
J 0
(-665 4035);
DISPLAY 0.680851 (-665 4035);
PAINT MONO (-665 4035);
FORCEPROP 0 LASTPIN (-675 4075) $PN 97
J 0
(-665 4085);
DISPLAY 0.680851 (-665 4085);
PAINT MONO (-665 4085);
FORCEPROP 0 LASTPIN (-675 4125) $PN 99
J 0
(-665 4135);
DISPLAY 0.680851 (-665 4135);
PAINT MONO (-665 4135);
FORCEPROP 0 LASTPIN (-675 4175) $PN 101
J 0
(-665 4185);
DISPLAY 0.680851 (-665 4185);
PAINT MONO (-665 4185);
FORCEPROP 0 LASTPIN (-675 4225) $PN 103
J 0
(-665 4235);
DISPLAY 0.680851 (-665 4235);
PAINT MONO (-665 4235);
FORCEPROP 0 LASTPIN (-675 4275) $PN 106
J 0
(-665 4285);
DISPLAY 0.680851 (-665 4285);
PAINT MONO (-665 4285);
FORCEPROP 0 LASTPIN (-675 4325) $PN 108
J 0
(-665 4335);
DISPLAY 0.680851 (-665 4335);
PAINT MONO (-665 4335);
FORCEPROP 0 LASTPIN (-675 4375) $PN 110
J 0
(-665 4385);
DISPLAY 0.680851 (-665 4385);
PAINT MONO (-665 4385);
FORCEPROP 0 LASTPIN (-675 4425) $PN 112
J 0
(-665 4435);
DISPLAY 0.680851 (-665 4435);
PAINT MONO (-665 4435);
FORCEPROP 0 LASTPIN (-675 4475) $PN 114
J 0
(-665 4485);
DISPLAY 0.680851 (-665 4485);
PAINT MONO (-665 4485);
FORCEPROP 0 LASTPIN (-675 4525) $PN 117
J 0
(-665 4535);
DISPLAY 0.680851 (-665 4535);
PAINT MONO (-665 4535);
FORCEPROP 0 LASTPIN (-675 4575) $PN 119
J 0
(-665 4585);
DISPLAY 0.680851 (-665 4585);
PAINT MONO (-665 4585);
FORCEPROP 0 LASTPIN (-675 4625) $PN 121
J 0
(-665 4635);
DISPLAY 0.680851 (-665 4635);
PAINT MONO (-665 4635);
FORCEPROP 0 LASTPIN (-675 4675) $PN 123
J 0
(-665 4685);
DISPLAY 0.680851 (-665 4685);
PAINT MONO (-665 4685);
FORCEPROP 0 LASTPIN (-675 4725) $PN 125
J 0
(-665 4735);
DISPLAY 0.680851 (-665 4735);
PAINT MONO (-665 4735);
FORCEPROP 0 LASTPIN (-675 4775) $PN 128
J 0
(-665 4785);
DISPLAY 0.680851 (-665 4785);
PAINT MONO (-665 4785);
FORCEPROP 0 LASTPIN (-675 4825) $PN 130
J 0
(-665 4835);
DISPLAY 0.680851 (-665 4835);
PAINT MONO (-665 4835);
FORCEPROP 0 LASTPIN (-675 4875) $PN 132
J 0
(-665 4885);
DISPLAY 0.680851 (-665 4885);
PAINT MONO (-665 4885);
FORCEPROP 0 LASTPIN (-675 4925) $PN 134
J 0
(-665 4935);
DISPLAY 0.680851 (-665 4935);
PAINT MONO (-665 4935);
FORCEPROP 0 LASTPIN (-675 4975) $PN 136
J 0
(-665 4985);
DISPLAY 0.680851 (-665 4985);
PAINT MONO (-665 4985);
FORCEPROP 0 LASTPIN (-675 5025) $PN 139
J 0
(-665 5035);
DISPLAY 0.680851 (-665 5035);
PAINT MONO (-665 5035);
FORCEPROP 0 LASTPIN (-675 5075) $PN 141
J 0
(-665 5085);
DISPLAY 0.680851 (-665 5085);
PAINT MONO (-665 5085);
FORCEPROP 0 LASTPIN (-675 5125) $PN 143
J 0
(-665 5135);
DISPLAY 0.680851 (-665 5135);
PAINT MONO (-665 5135);
FORCEPROP 0 LASTPIN (-1875 1875) $PN 151
J 2
(-1885 1885);
DISPLAY 0.680851 (-1885 1885);
PAINT MONO (-1885 1885);
FORCEPROP 0 LASTPIN (-1875 1925) $PN 153
J 2
(-1885 1935);
DISPLAY 0.680851 (-1885 1935);
PAINT MONO (-1885 1935);
FORCEPROP 0 LASTPIN (-1875 1975) $PN 155
J 2
(-1885 1985);
DISPLAY 0.680851 (-1885 1985);
PAINT MONO (-1885 1985);
FORCEPROP 0 LASTPIN (-1875 2025) $PN 158
J 2
(-1885 2035);
DISPLAY 0.680851 (-1885 2035);
PAINT MONO (-1885 2035);
FORCEPROP 0 LASTPIN (-1875 2075) $PN 160
J 2
(-1885 2085);
DISPLAY 0.680851 (-1885 2085);
PAINT MONO (-1885 2085);
FORCEPROP 0 LASTPIN (-1875 2125) $PN 162
J 2
(-1885 2135);
DISPLAY 0.680851 (-1885 2135);
PAINT MONO (-1885 2135);
FORCEPROP 0 LASTPIN (-1875 2175) $PN 164
J 2
(-1885 2185);
DISPLAY 0.680851 (-1885 2185);
PAINT MONO (-1885 2185);
FORCEPROP 0 LASTPIN (-1875 2225) $PN 166
J 2
(-1885 2235);
DISPLAY 0.680851 (-1885 2235);
PAINT MONO (-1885 2235);
FORCEPROP 0 LASTPIN (-1875 2275) $PN 169
J 2
(-1885 2285);
DISPLAY 0.680851 (-1885 2285);
PAINT MONO (-1885 2285);
FORCEPROP 0 LASTPIN (-1875 2325) $PN 171
J 2
(-1885 2335);
DISPLAY 0.680851 (-1885 2335);
PAINT MONO (-1885 2335);
FORCEPROP 0 LASTPIN (-1875 2375) $PN 173
J 2
(-1885 2385);
DISPLAY 0.680851 (-1885 2385);
PAINT MONO (-1885 2385);
FORCEPROP 0 LASTPIN (-1875 2425) $PN 175
J 2
(-1885 2435);
DISPLAY 0.680851 (-1885 2435);
PAINT MONO (-1885 2435);
FORCEPROP 0 LASTPIN (-1875 2475) $PN 177
J 2
(-1885 2485);
DISPLAY 0.680851 (-1885 2485);
PAINT MONO (-1885 2485);
FORCEPROP 0 LASTPIN (-1875 2525) $PN 180
J 2
(-1885 2535);
DISPLAY 0.680851 (-1885 2535);
PAINT MONO (-1885 2535);
FORCEPROP 0 LASTPIN (-1875 2575) $PN 182
J 2
(-1885 2585);
DISPLAY 0.680851 (-1885 2585);
PAINT MONO (-1885 2585);
FORCEPROP 0 LASTPIN (-1875 2625) $PN 184
J 2
(-1885 2635);
DISPLAY 0.680851 (-1885 2635);
PAINT MONO (-1885 2635);
FORCEPROP 0 LASTPIN (-1875 2675) $PN 186
J 2
(-1885 2685);
DISPLAY 0.680851 (-1885 2685);
PAINT MONO (-1885 2685);
FORCEPROP 0 LASTPIN (-1875 2725) $PN 188
J 2
(-1885 2735);
DISPLAY 0.680851 (-1885 2735);
PAINT MONO (-1885 2735);
FORCEPROP 0 LASTPIN (-1875 2775) $PN 191
J 2
(-1885 2785);
DISPLAY 0.680851 (-1885 2785);
PAINT MONO (-1885 2785);
FORCEPROP 0 LASTPIN (-1875 2825) $PN 193
J 2
(-1885 2835);
DISPLAY 0.680851 (-1885 2835);
PAINT MONO (-1885 2835);
FORCEPROP 0 LASTPIN (-1875 2875) $PN 195
J 2
(-1885 2885);
DISPLAY 0.680851 (-1885 2885);
PAINT MONO (-1885 2885);
FORCEPROP 0 LASTPIN (-1875 2925) $PN 197
J 2
(-1885 2935);
DISPLAY 0.680851 (-1885 2935);
PAINT MONO (-1885 2935);
FORCEPROP 0 LASTPIN (-1875 2975) $PN 199
J 2
(-1885 2985);
DISPLAY 0.680851 (-1885 2985);
PAINT MONO (-1885 2985);
FORCEPROP 0 LASTPIN (-1875 3025) $PN 202
J 2
(-1885 3035);
DISPLAY 0.680851 (-1885 3035);
PAINT MONO (-1885 3035);
FORCEPROP 0 LASTPIN (-1875 3075) $PN 204
J 2
(-1885 3085);
DISPLAY 0.680851 (-1885 3085);
PAINT MONO (-1885 3085);
FORCEPROP 0 LASTPIN (-1875 3125) $PN 206
J 2
(-1885 3135);
DISPLAY 0.680851 (-1885 3135);
PAINT MONO (-1885 3135);
FORCEPROP 0 LASTPIN (-1875 3175) $PN 208
J 2
(-1885 3185);
DISPLAY 0.680851 (-1885 3185);
PAINT MONO (-1885 3185);
FORCEPROP 0 LASTPIN (-1875 3225) $PN 210
J 2
(-1885 3235);
DISPLAY 0.680851 (-1885 3235);
PAINT MONO (-1885 3235);
FORCEPROP 0 LASTPIN (-1875 3275) $PN 212
J 2
(-1885 3285);
DISPLAY 0.680851 (-1885 3285);
PAINT MONO (-1885 3285);
FORCEPROP 0 LASTPIN (-1875 3325) $PN 214
J 2
(-1885 3335);
DISPLAY 0.680851 (-1885 3335);
PAINT MONO (-1885 3335);
FORCEPROP 0 LASTPIN (-1875 3375) $PN 216
J 2
(-1885 3385);
DISPLAY 0.680851 (-1885 3385);
PAINT MONO (-1885 3385);
FORCEPROP 0 LASTPIN (-1875 3425) $PN 219
J 2
(-1885 3435);
DISPLAY 0.680851 (-1885 3435);
PAINT MONO (-1885 3435);
FORCEPROP 0 LASTPIN (-1875 3475) $PN 222
J 2
(-1885 3485);
DISPLAY 0.680851 (-1885 3485);
PAINT MONO (-1885 3485);
FORCEPROP 0 LASTPIN (-1875 3525) $PN 224
J 2
(-1885 3535);
DISPLAY 0.680851 (-1885 3535);
PAINT MONO (-1885 3535);
FORCEPROP 0 LASTPIN (-1875 3575) $PN 226
J 2
(-1885 3585);
DISPLAY 0.680851 (-1885 3585);
PAINT MONO (-1885 3585);
FORCEPROP 0 LASTPIN (-1875 3625) $PN 228
J 2
(-1885 3635);
DISPLAY 0.680851 (-1885 3635);
PAINT MONO (-1885 3635);
FORCEPROP 0 LASTPIN (-1875 3675) $PN 230
J 2
(-1885 3685);
DISPLAY 0.680851 (-1885 3685);
PAINT MONO (-1885 3685);
FORCEPROP 0 LASTPIN (-1875 3725) $PN 233
J 2
(-1885 3735);
DISPLAY 0.680851 (-1885 3735);
PAINT MONO (-1885 3735);
FORCEPROP 0 LASTPIN (-1875 3775) $PN 235
J 2
(-1885 3785);
DISPLAY 0.680851 (-1885 3785);
PAINT MONO (-1885 3785);
FORCEPROP 0 LASTPIN (-1875 3825) $PN 237
J 2
(-1885 3835);
DISPLAY 0.680851 (-1885 3835);
PAINT MONO (-1885 3835);
FORCEPROP 0 LASTPIN (-1875 3875) $PN 240
J 2
(-1885 3885);
DISPLAY 0.680851 (-1885 3885);
PAINT MONO (-1885 3885);
FORCEPROP 0 LASTPIN (-1875 3925) $PN 242
J 2
(-1885 3935);
DISPLAY 0.680851 (-1885 3935);
PAINT MONO (-1885 3935);
FORCEPROP 0 LASTPIN (-1875 3975) $PN 244
J 2
(-1885 3985);
DISPLAY 0.680851 (-1885 3985);
PAINT MONO (-1885 3985);
FORCEPROP 0 LASTPIN (-1875 4025) $PN 246
J 2
(-1885 4035);
DISPLAY 0.680851 (-1885 4035);
PAINT MONO (-1885 4035);
FORCEPROP 0 LASTPIN (-1875 4075) $PN 248
J 2
(-1885 4085);
DISPLAY 0.680851 (-1885 4085);
PAINT MONO (-1885 4085);
FORCEPROP 0 LASTPIN (-1875 4125) $PN 251
J 2
(-1885 4135);
DISPLAY 0.680851 (-1885 4135);
PAINT MONO (-1885 4135);
FORCEPROP 0 LASTPIN (-1875 4175) $PN 253
J 2
(-1885 4185);
DISPLAY 0.680851 (-1885 4185);
PAINT MONO (-1885 4185);
FORCEPROP 0 LASTPIN (-1875 4225) $PN 255
J 2
(-1885 4235);
DISPLAY 0.680851 (-1885 4235);
PAINT MONO (-1885 4235);
FORCEPROP 0 LASTPIN (-1875 4275) $PN 257
J 2
(-1885 4285);
DISPLAY 0.680851 (-1885 4285);
PAINT MONO (-1885 4285);
FORCEPROP 0 LASTPIN (-1875 4325) $PN 259
J 2
(-1885 4335);
DISPLAY 0.680851 (-1885 4335);
PAINT MONO (-1885 4335);
FORCEPROP 0 LASTPIN (-1875 4375) $PN 262
J 2
(-1885 4385);
DISPLAY 0.680851 (-1885 4385);
PAINT MONO (-1885 4385);
FORCEPROP 0 LASTPIN (-1875 4425) $PN 264
J 2
(-1885 4435);
DISPLAY 0.680851 (-1885 4435);
PAINT MONO (-1885 4435);
FORCEPROP 0 LASTPIN (-1875 4475) $PN 266
J 2
(-1885 4485);
DISPLAY 0.680851 (-1885 4485);
PAINT MONO (-1885 4485);
FORCEPROP 0 LASTPIN (-1875 4525) $PN 268
J 2
(-1885 4535);
DISPLAY 0.680851 (-1885 4535);
PAINT MONO (-1885 4535);
FORCEPROP 0 LASTPIN (-1875 4575) $PN 270
J 2
(-1885 4585);
DISPLAY 0.680851 (-1885 4585);
PAINT MONO (-1885 4585);
FORCEPROP 0 LASTPIN (-1875 4625) $PN 273
J 2
(-1885 4635);
DISPLAY 0.680851 (-1885 4635);
PAINT MONO (-1885 4635);
FORCEPROP 0 LASTPIN (-1875 4675) $PN 275
J 2
(-1885 4685);
DISPLAY 0.680851 (-1885 4685);
PAINT MONO (-1885 4685);
FORCEPROP 0 LASTPIN (-1875 4725) $PN 277
J 2
(-1885 4735);
DISPLAY 0.680851 (-1885 4735);
PAINT MONO (-1885 4735);
FORCEPROP 0 LASTPIN (-1875 4775) $PN 279
J 2
(-1885 4785);
DISPLAY 0.680851 (-1885 4785);
PAINT MONO (-1885 4785);
FORCEPROP 0 LASTPIN (-1875 4825) $PN 281
J 2
(-1885 4835);
DISPLAY 0.680851 (-1885 4835);
PAINT MONO (-1885 4835);
FORCEPROP 0 LASTPIN (-1875 4875) $PN 284
J 2
(-1885 4885);
DISPLAY 0.680851 (-1885 4885);
PAINT MONO (-1885 4885);
FORCEPROP 0 LASTPIN (-1875 4925) $PN 286
J 2
(-1885 4935);
DISPLAY 0.680851 (-1885 4935);
PAINT MONO (-1885 4935);
FORCEPROP 0 LASTPIN (-1875 4975) $PN 288
J 2
(-1885 4985);
DISPLAY 0.680851 (-1885 4985);
PAINT MONO (-1885 4985);
FORCEPROP 2 LAST PART_TYPE SMLF
J 0
(-1725 5550);
DISPLAY 1.021277 (-1725 5550);
FORCEPROP 2 LAST VALUE SCONN288_DDR506112002KQ
J 0
(-1725 5500);
DISPLAY 0.489362 (-1725 5500);
PAINT SKYBLUE (-1725 5500);
FORCEPROP 1 LAST MATERIAL IO
J 0
(-1725 5300);
DISPLAY 0.468085 (-1725 5300);
PAINT SKYBLUE (-1725 5300);
FORCEPROP 1 LAST PART_NUMBER DFHST8FS479
J 0
(-1725 5375);
DISPLAY 0.468085 (-1725 5375);
PAINT SKYBLUE (-1725 5375);
FORCEPROP 1 LAST CDS_LMAN_SYM_OUTLINE -450,1800,450,-1750
J 0
(-1275 3475);
DISPLAY 0.468085 (-1275 3475);
PAINT GREEN (-1275 3475);
DISPLAY INVISIBLE (-1275 3475);
FORCEPROP 1 LAST PATH I160
J 0
(-1275 3475);
DISPLAY 0.723404 (-1275 3475);
PAINT GREEN (-1275 3475);
DISPLAY INVISIBLE (-1275 3475);
FORCEPROP 1 LAST NEEDS_NO_SIZE TRUE
J 0
(-1275 3475);
DISPLAY 0.723404 (-1275 3475);
PAINT GREEN (-1275 3475);
DISPLAY INVISIBLE (-1275 3475);
FORCEPROP 2 LAST CDS_LIB pure_quanta
J 0
(-1275 3475);
DISPLAY INVISIBLE (-1275 3475);
FORCEADD GND..1
(-375 1550);
FORCEPROP 3 LASTPIN (-375 1600) SIG_NAME GND\g
J 0
(-365 1610);
DISPLAY 0.659574 (-365 1610);
PAINT MONO (-365 1610);
DISPLAY INVISIBLE (-365 1610);
FORCEPROP 2 LAST CDS_LIB mstr_symbols
J 0
(-375 1550);
DISPLAY 0.723404 (-375 1550);
DISPLAY INVISIBLE (-375 1550);
FORCEPROP 1 LAST SIZE 1B
J 0
(-300 1500);
DISPLAY 0.851064 (-300 1500);
PAINT GREEN (-300 1500);
DISPLAY INVISIBLE (-300 1500);
FORCEPROP 1 LAST BODY_TYPE PLUMBING
J 0
(-420 1507);
DISPLAY 0.340426 (-420 1507);
PAINT GREEN (-420 1507);
DISPLAY INVISIBLE (-420 1507);
FORCEPROP 1 LAST PATH I161
J 0
(-300 1550);
DISPLAY 0.872340 (-300 1550);
PAINT AQUA (-300 1550);
DISPLAY INVISIBLE (-300 1550);
FORCEPROP 1 LAST VOLTAGE 0.0
J 0
(-420 1507);
DISPLAY 0.723404 (-420 1507);
PAINT SKYBLUE (-420 1507);
DISPLAY INVISIBLE (-420 1507);
FORCEPROP 1 LAST HDL_POWER GND
J 0
(-375 1700);
DISPLAY 0.851064 (-375 1700);
PAINT GREEN (-375 1700);
DISPLAY INVISIBLE (-375 1700);
FORCEADD OFFPAGE..1
(-8375 4275);
FORCEPROP 2 LAST $XR0 38 
J 0
(-8626 4275);
DISPLAY 0.638298 (-8626 4275);
PAINT MONO (-8626 4275);
FORCEPROP 2 LAST PATH I17
J 0
(-8575 4325);
DISPLAY 1.021277 (-8575 4325);
DISPLAY INVISIBLE (-8575 4325);
FORCEPROP 1 LAST COMMENT_BODY TRUE
J 0
(-8250 4175);
DISPLAY 0.872340 (-8250 4175);
PAINT GREEN (-8250 4175);
DISPLAY INVISIBLE (-8250 4175);
FORCEPROP 1 LAST OFFPAGE TRUE
J 0
(-8050 4150);
DISPLAY 0.872340 (-8050 4150);
PAINT GREEN (-8050 4150);
DISPLAY INVISIBLE (-8050 4150);
FORCEPROP 2 LAST CDS_LIB mstr_standard
J 0
(-8375 4275);
DISPLAY 0.723404 (-8375 4275);
PAINT MONO (-8375 4275);
DISPLAY INVISIBLE (-8375 4275);
FORCEADD OFFPAGE..6
(-8375 2975);
FORCEPROP 2 LAST $XR5 136 
J 0
(-9224 2975);
DISPLAY 0.638298 (-9224 2975);
PAINT MONO (-9224 2975);
FORCEPROP 2 LAST $XR4 102 
J 0
(-9104 2975);
DISPLAY 0.638298 (-9104 2975);
PAINT MONO (-9104 2975);
FORCEPROP 2 LAST $XR3 101 
J 0
(-8984 2975);
DISPLAY 0.638298 (-8984 2975);
PAINT MONO (-8984 2975);
FORCEPROP 2 LAST $XR2 100 
J 0
(-8864 2975);
DISPLAY 0.638298 (-8864 2975);
PAINT MONO (-8864 2975);
FORCEPROP 2 LAST $XR1 99 
J 0
(-8744 2975);
DISPLAY 0.638298 (-8744 2975);
PAINT MONO (-8744 2975);
FORCEPROP 2 LAST $XR0 97 
J 0
(-8654 2975);
DISPLAY 0.638298 (-8654 2975);
PAINT MONO (-8654 2975);
FORCEPROP 2 LAST PATH I179
J 0
(-8650 3025);
DISPLAY 1.021277 (-8650 3025);
DISPLAY INVISIBLE (-8650 3025);
FORCEPROP 1 LAST COMMENT_BODY TRUE
J 0
(-8275 2900);
DISPLAY 0.872340 (-8275 2900);
PAINT GREEN (-8275 2900);
DISPLAY INVISIBLE (-8275 2900);
FORCEPROP 1 LAST OFFPAGE TRUE
J 0
(-8050 2850);
DISPLAY 0.872340 (-8050 2850);
PAINT GREEN (-8050 2850);
DISPLAY INVISIBLE (-8050 2850);
FORCEPROP 2 LAST CDS_LIB mstr_standard
J 0
(-8375 2975);
DISPLAY 0.808511 (-8375 2975);
DISPLAY INVISIBLE (-8375 2975);
FORCEADD OFFPAGE..1
(-8375 4225);
FORCEPROP 2 LAST $XR0 38 
J 0
(-8626 4225);
DISPLAY 0.638298 (-8626 4225);
PAINT MONO (-8626 4225);
FORCEPROP 2 LAST PATH I18
J 0
(-8575 4275);
DISPLAY 1.021277 (-8575 4275);
DISPLAY INVISIBLE (-8575 4275);
FORCEPROP 1 LAST COMMENT_BODY TRUE
J 0
(-8250 4125);
DISPLAY 0.872340 (-8250 4125);
PAINT GREEN (-8250 4125);
DISPLAY INVISIBLE (-8250 4125);
FORCEPROP 1 LAST OFFPAGE TRUE
J 0
(-8050 4100);
DISPLAY 0.872340 (-8050 4100);
PAINT GREEN (-8050 4100);
DISPLAY INVISIBLE (-8050 4100);
FORCEPROP 2 LAST CDS_LIB mstr_standard
J 0
(-8375 4225);
DISPLAY 0.808511 (-8375 4225);
DISPLAY INVISIBLE (-8375 4225);
FORCEADD Q_CAP..1
R 2
(-8725 3325);
FORCEPROP 1 LAST LOCATION C140
J 2
(-8775 3425);
DISPLAY 0.489362 (-8775 3425);
PAINT SKYBLUE (-8775 3425);
FORCEPROP 0 LAST $SEC 1
J 0
(-8775 3475);
DISPLAY 0.680851 (-8775 3475);
PAINT MONO (-8775 3475);
DISPLAY INVISIBLE (-8775 3475);
FORCEPROP 0 LAST CDS_SEC 1
J 0
(-8775 3475);
DISPLAY 1.021277 (-8775 3475);
DISPLAY INVISIBLE (-8775 3475);
FORCEPROP 1 LASTPIN (-8725 3425) $PN 1
J 2
(-8735 3405);
DISPLAY 0.489362 (-8735 3405);
PAINT MONO (-8735 3405);
FORCEPROP 1 LASTPIN (-8725 3225) $PN 2
J 2
(-8735 3205);
DISPLAY 0.489362 (-8735 3205);
PAINT MONO (-8735 3205);
FORCEPROP 1 LAST MATERIAL X7R
J 2
(-8775 3225);
DISPLAY 0.489362 (-8775 3225);
PAINT SKYBLUE (-8775 3225);
FORCEPROP 1 LAST TOLERANCE 10%
J 2
(-8775 3275);
DISPLAY 0.489362 (-8775 3275);
PAINT SKYBLUE (-8775 3275);
FORCEPROP 1 LAST VALUE 0.1UF
J 2
(-8775 3375);
DISPLAY 0.489362 (-8775 3375);
PAINT SKYBLUE (-8775 3375);
FORCEPROP 1 LAST VOLTAGE 25V
J 2
(-8775 3325);
DISPLAY 0.489362 (-8775 3325);
PAINT SKYBLUE (-8775 3325);
FORCEPROP 1 LAST PART_NUMBER CH4104K1B00
J 2
(-8775 3175);
DISPLAY 0.489362 (-8775 3175);
PAINT SKYBLUE (-8775 3175);
FORCEPROP 1 LAST PACK_TYPE 0402
J 2
(-8775 3125);
DISPLAY 0.489362 (-8775 3125);
PAINT SKYBLUE (-8775 3125);
FORCEPROP 0 LAST BOM_COST MEM
J 2
(-8780 3470);
DISPLAY 0.595745 (-8780 3470);
PAINT MONO (-8780 3470);
DISPLAY INVISIBLE (-8780 3470);
FORCEPROP 2 LAST CDS_LIB pure_quanta
J 0
(-8725 3325);
DISPLAY INVISIBLE (-8725 3325);
FORCEPROP 1 LAST PATH I185
J 2
(-8775 3475);
DISPLAY 0.978723 (-8775 3475);
PAINT WHITE (-8775 3475);
DISPLAY INVISIBLE (-8775 3475);
FORCEPROP 0 LAST ROOM MEM_CH_A_CPU0_DIMM1
J 2
(-8780 3470);
DISPLAY 0.595745 (-8780 3470);
PAINT RED (-8780 3470);
DISPLAY INVISIBLE (-8780 3470);
FORCEADD GND..1
(-8725 3100);
FORCEPROP 3 LASTPIN (-8725 3150) SIG_NAME GND\g
J 0
(-8715 3160);
DISPLAY 0.659574 (-8715 3160);
PAINT MONO (-8715 3160);
DISPLAY INVISIBLE (-8715 3160);
FORCEPROP 2 LAST BOM_COST MEM
J 0
(-8700 3225);
DISPLAY 0.659574 (-8700 3225);
DISPLAY INVISIBLE (-8700 3225);
FORCEPROP 1 LAST SIZE 1B
J 0
(-8650 3050);
DISPLAY 0.723404 (-8650 3050);
PAINT GREEN (-8650 3050);
DISPLAY INVISIBLE (-8650 3050);
FORCEPROP 2 LAST CDS_LIB mstr_symbols
J 0
(-8725 3100);
DISPLAY 0.808511 (-8725 3100);
DISPLAY INVISIBLE (-8725 3100);
FORCEPROP 1 LAST BODY_TYPE PLUMBING
J 0
(-8770 3057);
DISPLAY 0.276596 (-8770 3057);
PAINT GREEN (-8770 3057);
DISPLAY INVISIBLE (-8770 3057);
FORCEPROP 1 LAST PATH I186
J 0
(-8650 3100);
DISPLAY 0.872340 (-8650 3100);
PAINT AQUA (-8650 3100);
DISPLAY INVISIBLE (-8650 3100);
FORCEPROP 1 LAST VOLTAGE 0
J 0
(-8745 3195);
DISPLAY 0.829787 (-8745 3195);
PAINT SKYBLUE (-8745 3195);
DISPLAY INVISIBLE (-8745 3195);
FORCEPROP 2 LAST ROOM MEM_EFGH_DECOUPLING_CAPS
J 0
(-8700 3175);
DISPLAY 0.659574 (-8700 3175);
PAINT RED (-8700 3175);
DISPLAY INVISIBLE (-8700 3175);
FORCEPROP 1 LAST HDL_POWER GND
J 0
(-8725 3250);
DISPLAY 0.723404 (-8725 3250);
PAINT GREEN (-8725 3250);
DISPLAY INVISIBLE (-8725 3250);
FORCEADD OFFPAGE..6
(-9125 2275);
FORCEPROP 2 LAST $XR5 81 
J 0
(-9374 2095);
DISPLAY 0.638298 (-9374 2095);
PAINT MONO (-9374 2095);
FORCEPROP 2 LAST $XR4 102 
J 0
(-9374 2131);
DISPLAY 0.638298 (-9374 2131);
PAINT MONO (-9374 2131);
FORCEPROP 2 LAST $XR3 101 
J 0
(-9374 2167);
DISPLAY 0.638298 (-9374 2167);
PAINT MONO (-9374 2167);
FORCEPROP 2 LAST $XR2 100 
J 0
(-9374 2203);
DISPLAY 0.638298 (-9374 2203);
PAINT MONO (-9374 2203);
FORCEPROP 2 LAST $XR1 99 
J 0
(-9374 2239);
DISPLAY 0.638298 (-9374 2239);
PAINT MONO (-9374 2239);
FORCEPROP 2 LAST $XR0 97 
J 0
(-9374 2275);
DISPLAY 0.638298 (-9374 2275);
PAINT MONO (-9374 2275);
FORCEPROP 2 LAST PATH I187
J 0
(-9075 2350);
DISPLAY 1.021277 (-9075 2350);
DISPLAY INVISIBLE (-9075 2350);
FORCEPROP 1 LAST COMMENT_BODY TRUE
J 0
(-9025 2200);
DISPLAY 0.872340 (-9025 2200);
PAINT GREEN (-9025 2200);
DISPLAY INVISIBLE (-9025 2200);
FORCEPROP 1 LAST OFFPAGE TRUE
J 0
(-8800 2150);
DISPLAY 0.872340 (-8800 2150);
PAINT GREEN (-8800 2150);
DISPLAY INVISIBLE (-8800 2150);
FORCEPROP 2 LAST CDS_LIB mstr_standard
J 0
(-9125 2275);
DISPLAY 0.808511 (-9125 2275);
DISPLAY INVISIBLE (-9125 2275);
FORCEADD Q_RES..1
R 2
(-8625 2275);
FORCEPROP 1 LAST LOCATION R304
J 2
(-8600 2300);
DISPLAY 0.489362 (-8600 2300);
PAINT SKYBLUE (-8600 2300);
FORCEPROP 0 LAST $SEC 1
J 0
(-8600 2350);
DISPLAY 0.680851 (-8600 2350);
PAINT MONO (-8600 2350);
DISPLAY INVISIBLE (-8600 2350);
FORCEPROP 0 LAST CDS_SEC 1
J 0
(-8600 2350);
DISPLAY 1.021277 (-8600 2350);
DISPLAY INVISIBLE (-8600 2350);
FORCEPROP 1 LASTPIN (-8525 2275) $PN 1
J 2
(-8537 2287);
DISPLAY 0.489362 (-8537 2287);
PAINT MONO (-8537 2287);
FORCEPROP 1 LASTPIN (-8725 2275) $PN 2
J 2
(-8687 2287);
DISPLAY 0.489362 (-8687 2287);
PAINT MONO (-8687 2287);
FORCEPROP 1 LAST VALUE 0
J 0
(-8625 2225);
DISPLAY 0.489362 (-8625 2225);
PAINT SKYBLUE (-8625 2225);
FORCEPROP 2 LAST BOM_COST MEM
J 0
(-8650 2425);
DISPLAY 0.744681 (-8650 2425);
PAINT WHITE (-8650 2425);
DISPLAY INVISIBLE (-8650 2425);
FORCEPROP 2 LAST CDS_LIB pure_quanta
J 0
(-8625 2275);
DISPLAY INVISIBLE (-8625 2275);
FORCEPROP 1 LAST PATH I188
J 2
(-8575 2425);
DISPLAY 0.978723 (-8575 2425);
PAINT WHITE (-8575 2425);
DISPLAY INVISIBLE (-8575 2425);
FORCEPROP 1 LAST WATTAGE 1/16W
J 0
(-8550 2200);
DISPLAY 0.489362 (-8550 2200);
PAINT SKYBLUE (-8550 2200);
DISPLAY INVISIBLE (-8550 2200);
FORCEPROP 1 LAST MATERIAL CHIP
J 0
(-8800 2250);
DISPLAY 0.489362 (-8800 2250);
PAINT SKYBLUE (-8800 2250);
DISPLAY INVISIBLE (-8800 2250);
FORCEPROP 1 LAST TOLERANCE 5%
J 2
(-8500 2250);
DISPLAY 0.489362 (-8500 2250);
PAINT SKYBLUE (-8500 2250);
DISPLAY INVISIBLE (-8500 2250);
FORCEPROP 1 LAST PART_NUMBER CS00002JB38
J 0
(-8725 2325);
DISPLAY 0.489362 (-8725 2325);
PAINT SKYBLUE (-8725 2325);
DISPLAY INVISIBLE (-8725 2325);
FORCEPROP 1 LAST PACK_TYPE 0402LF
J 0
(-8800 2200);
DISPLAY 0.489362 (-8800 2200);
PAINT SKYBLUE (-8800 2200);
DISPLAY INVISIBLE (-8800 2200);
FORCEPROP 2 LAST ROOM RST_CPU0_PLD_TO_DIMM
J 0
(-8650 2375);
DISPLAY 0.744681 (-8650 2375);
PAINT RED (-8650 2375);
DISPLAY INVISIBLE (-8650 2375);
FORCEADD VCC_CORE..1
(-8500 2600);
FORCEPROP 3 LASTPIN (-8500 2550) SIG_NAME P3V3_STBY\g
J 0
(-8490 2560);
DISPLAY 0.659574 (-8490 2560);
PAINT MONO (-8490 2560);
DISPLAY INVISIBLE (-8490 2560);
FORCEPROP 1 LAST HDL_POWER P3V3_STBY
J 1
(-8500 2650);
DISPLAY 0.489362 (-8500 2650);
PAINT GREEN (-8500 2650);
FORCEPROP 2 LAST CDS_LIB mstr_symbols
J 0
(-8500 2600);
DISPLAY INVISIBLE (-8500 2600);
FORCEPROP 1 LAST PATH I189
J 0
(-8450 2625);
DISPLAY 0.872340 (-8450 2625);
PAINT AQUA (-8450 2625);
DISPLAY INVISIBLE (-8450 2625);
FORCEPROP 0 LAST VOLTAGE 3.3
J 0
(-8775 2750);
DISPLAY 1.021277 (-8775 2750);
PAINT SKYBLUE (-8775 2750);
DISPLAY INVISIBLE (-8775 2750);
FORCEPROP 2 LAST ROOM PVCCINFAON_CPU0_CTRL
J 0
(-8500 2700);
DISPLAY 0.808511 (-8500 2700);
PAINT RED (-8500 2700);
DISPLAY INVISIBLE (-8500 2700);
FORCEADD OFFPAGE..6
(-8375 4175);
FORCEPROP 2 LAST $XR0 38 
J 0
(-8654 4175);
DISPLAY 0.638298 (-8654 4175);
PAINT MONO (-8654 4175);
FORCEPROP 2 LAST PATH I19
J 0
(-8600 4225);
DISPLAY 1.021277 (-8600 4225);
DISPLAY INVISIBLE (-8600 4225);
FORCEPROP 1 LAST COMMENT_BODY TRUE
J 0
(-8275 4100);
DISPLAY 0.872340 (-8275 4100);
PAINT GREEN (-8275 4100);
DISPLAY INVISIBLE (-8275 4100);
FORCEPROP 1 LAST OFFPAGE TRUE
J 0
(-8050 4050);
DISPLAY 0.872340 (-8050 4050);
PAINT GREEN (-8050 4050);
DISPLAY INVISIBLE (-8050 4050);
FORCEPROP 2 LAST CDS_LIB mstr_standard
J 0
(-8375 4175);
DISPLAY 0.723404 (-8375 4175);
PAINT MONO (-8375 4175);
DISPLAY INVISIBLE (-8375 4175);
FORCEADD Q_RES..2
(-8500 2425);
FORCEPROP 1 LAST LOCATION R104
J 0
(-8455 2550);
DISPLAY 0.489362 (-8455 2550);
PAINT SKYBLUE (-8455 2550);
FORCEPROP 0 LAST $SEC 1
J 0
(-8450 2600);
DISPLAY 0.680851 (-8450 2600);
PAINT MONO (-8450 2600);
DISPLAY INVISIBLE (-8450 2600);
FORCEPROP 0 LAST CDS_SEC 1
J 0
(-8450 2600);
DISPLAY 1.021277 (-8450 2600);
DISPLAY INVISIBLE (-8450 2600);
FORCEPROP 1 LASTPIN (-8500 2525) $PN 1
J 0
(-8495 2487);
DISPLAY 0.489362 (-8495 2487);
PAINT MONO (-8495 2487);
FORCEPROP 1 LASTPIN (-8500 2325) $PN 2
J 0
(-8495 2335);
DISPLAY 0.489362 (-8495 2335);
PAINT MONO (-8495 2335);
FORCEPROP 1 LAST MATERIAL EMPTY
J 0
(-8450 2425);
DISPLAY 0.489362 (-8450 2425);
PAINT RED (-8450 2425);
FORCEPROP 1 LAST VALUE 1K
J 0
(-8455 2500);
DISPLAY 0.489362 (-8455 2500);
PAINT SKYBLUE (-8455 2500);
FORCEPROP 1 LAST PACK_TYPE 0402LF
J 0
(-8450 2375);
DISPLAY 0.489362 (-8450 2375);
PAINT SKYBLUE (-8450 2375);
FORCEPROP 1 LAST WATTAGE 1/16W
J 0
(-8450 2450);
DISPLAY 0.489362 (-8450 2450);
PAINT SKYBLUE (-8450 2450);
FORCEPROP 1 LAST TOLERANCE 5%
J 0
(-8450 2475);
DISPLAY 0.489362 (-8450 2475);
PAINT SKYBLUE (-8450 2475);
FORCEPROP 2 LAST CDS_LIB pure_quanta
J 2
(-8500 2425);
DISPLAY INVISIBLE (-8500 2425);
FORCEPROP 2 LAST BOM_COST MEM
J 0
(-8450 2600);
DISPLAY 0.808511 (-8450 2600);
DISPLAY INVISIBLE (-8450 2600);
FORCEPROP 1 LAST PATH I190
J 0
(-8450 2600);
DISPLAY 0.978723 (-8450 2600);
PAINT WHITE (-8450 2600);
DISPLAY INVISIBLE (-8450 2600);
FORCEPROP 1 LAST PART_NUMBER TMP_QCS21002JB34
J 0
(-8450 2400);
DISPLAY 0.489362 (-8450 2400);
PAINT SKYBLUE (-8450 2400);
DISPLAY INVISIBLE (-8450 2400);
FORCEPROP 2 LAST ROOM MEM_CH_A_CPU0_DIMM1
J 0
(-8450 2650);
DISPLAY 0.808511 (-8450 2650);
PAINT RED (-8450 2650);
DISPLAY INVISIBLE (-8450 2650);
FORCEADD TAP..1
(-3250 3750);
FORCEPROP 3 LASTPIN (-3300 3750) SIG_NAME M_B_CPU1_SA_DQS_DN<2>
J 0
(-3290 3760);
DISPLAY 0.659574 (-3290 3760);
PAINT MONO (-3290 3760);
DISPLAY INVISIBLE (-3290 3760);
FORCEPROP 1 LASTPIN (-3300 3750) BN 2
J 0
(-3312 3758);
DISPLAY 0.489362 (-3312 3758);
PAINT GREEN (-3312 3758);
FORCEPROP 2 LAST CDS_LIB mstr_standard
J 0
(-3250 3750);
DISPLAY 0.723404 (-3250 3750);
PAINT MONO (-3250 3750);
DISPLAY INVISIBLE (-3250 3750);
FORCEPROP 1 LAST BODY_TYPE PLUMBING
J 0
(-3250 3800);
DISPLAY 0.872340 (-3250 3800);
PAINT GREEN (-3250 3800);
DISPLAY INVISIBLE (-3250 3800);
FORCEPROP 1 LAST HDL_TAP TRUE
J 0
(-2925 3625);
DISPLAY 0.872340 (-2925 3625);
DISPLAY INVISIBLE (-2925 3625);
FORCEPROP 1 LAST PATH I191
J 0
(-3252 3750);
DISPLAY 0.872340 (-3252 3750);
PAINT GREEN (-3252 3750);
DISPLAY INVISIBLE (-3252 3750);
FORCEADD OFFPAGE..2
(-2450 4550);
FORCEPROP 2 LAST $XR0 38 
J 0
(-2261 4550);
DISPLAY 0.638298 (-2261 4550);
PAINT MONO (-2261 4550);
FORCEPROP 1 LAST COMMENT_BODY TRUE
J 0
(-2495 4455);
DISPLAY 0.872340 (-2495 4455);
PAINT GREEN (-2495 4455);
DISPLAY INVISIBLE (-2495 4455);
FORCEPROP 1 LAST OFFPAGE TRUE
J 0
(-2125 4425);
DISPLAY 0.723404 (-2125 4425);
PAINT GREEN (-2125 4425);
DISPLAY INVISIBLE (-2125 4425);
FORCEPROP 2 LAST CDS_LIB mstr_standard
J 0
(-2450 4550);
DISPLAY 0.723404 (-2450 4550);
PAINT MONO (-2450 4550);
DISPLAY INVISIBLE (-2450 4550);
FORCEPROP 2 LAST PATH I193
J 0
(-2250 4600);
DISPLAY 0.680851 (-2250 4600);
DISPLAY INVISIBLE (-2250 4600);
FORCEADD OFFPAGE..2
(-2450 4500);
FORCEPROP 2 LAST $XR0 38 
J 0
(-2261 4500);
DISPLAY 0.638298 (-2261 4500);
PAINT MONO (-2261 4500);
FORCEPROP 1 LAST COMMENT_BODY TRUE
J 0
(-2495 4405);
DISPLAY 0.872340 (-2495 4405);
PAINT GREEN (-2495 4405);
DISPLAY INVISIBLE (-2495 4405);
FORCEPROP 1 LAST OFFPAGE TRUE
J 0
(-2125 4375);
DISPLAY 0.723404 (-2125 4375);
PAINT GREEN (-2125 4375);
DISPLAY INVISIBLE (-2125 4375);
FORCEPROP 2 LAST CDS_LIB mstr_standard
J 0
(-2450 4500);
DISPLAY 0.723404 (-2450 4500);
PAINT MONO (-2450 4500);
DISPLAY INVISIBLE (-2450 4500);
FORCEPROP 2 LAST PATH I194
J 0
(-2250 4550);
DISPLAY 0.680851 (-2250 4550);
DISPLAY INVISIBLE (-2250 4550);
FORCEADD TAP..1
(-3250 4450);
FORCEPROP 3 LASTPIN (-3300 4450) SIG_NAME M_B_CPU1_SA_DQS_DN<9>
J 0
(-3290 4460);
DISPLAY 0.659574 (-3290 4460);
PAINT MONO (-3290 4460);
DISPLAY INVISIBLE (-3290 4460);
FORCEPROP 1 LASTPIN (-3300 4450) BN 9
J 0
(-3312 4458);
DISPLAY 0.489362 (-3312 4458);
PAINT GREEN (-3312 4458);
FORCEPROP 2 LAST CDS_LIB mstr_standard
J 0
(-3250 4450);
DISPLAY 0.723404 (-3250 4450);
PAINT MONO (-3250 4450);
DISPLAY INVISIBLE (-3250 4450);
FORCEPROP 1 LAST BODY_TYPE PLUMBING
J 0
(-3250 4500);
DISPLAY 0.872340 (-3250 4500);
PAINT GREEN (-3250 4500);
DISPLAY INVISIBLE (-3250 4500);
FORCEPROP 1 LAST HDL_TAP TRUE
J 0
(-2925 4325);
DISPLAY 0.872340 (-2925 4325);
DISPLAY INVISIBLE (-2925 4325);
FORCEPROP 1 LAST PATH I195
J 0
(-3252 4450);
DISPLAY 0.872340 (-3252 4450);
PAINT GREEN (-3252 4450);
DISPLAY INVISIBLE (-3252 4450);
FORCEADD TAP..1
(-3250 4350);
FORCEPROP 3 LASTPIN (-3300 4350) SIG_NAME M_B_CPU1_SA_DQS_DN<8>
J 0
(-3290 4360);
DISPLAY 0.659574 (-3290 4360);
PAINT MONO (-3290 4360);
DISPLAY INVISIBLE (-3290 4360);
FORCEPROP 1 LASTPIN (-3300 4350) BN 8
J 0
(-3312 4358);
DISPLAY 0.489362 (-3312 4358);
PAINT GREEN (-3312 4358);
FORCEPROP 2 LAST CDS_LIB mstr_standard
J 0
(-3250 4350);
DISPLAY 0.723404 (-3250 4350);
PAINT MONO (-3250 4350);
DISPLAY INVISIBLE (-3250 4350);
FORCEPROP 1 LAST BODY_TYPE PLUMBING
J 0
(-3250 4400);
DISPLAY 0.872340 (-3250 4400);
PAINT GREEN (-3250 4400);
DISPLAY INVISIBLE (-3250 4400);
FORCEPROP 1 LAST HDL_TAP TRUE
J 0
(-2925 4225);
DISPLAY 0.872340 (-2925 4225);
DISPLAY INVISIBLE (-2925 4225);
FORCEPROP 1 LAST PATH I196
J 0
(-3252 4350);
DISPLAY 0.872340 (-3252 4350);
PAINT GREEN (-3252 4350);
DISPLAY INVISIBLE (-3252 4350);
FORCEADD TAP..1
(-3250 4250);
FORCEPROP 3 LASTPIN (-3300 4250) SIG_NAME M_B_CPU1_SA_DQS_DN<7>
J 0
(-3290 4260);
DISPLAY 0.659574 (-3290 4260);
PAINT MONO (-3290 4260);
DISPLAY INVISIBLE (-3290 4260);
FORCEPROP 1 LASTPIN (-3300 4250) BN 7
J 0
(-3312 4258);
DISPLAY 0.489362 (-3312 4258);
PAINT GREEN (-3312 4258);
FORCEPROP 2 LAST CDS_LIB mstr_standard
J 0
(-3250 4250);
DISPLAY 0.723404 (-3250 4250);
PAINT MONO (-3250 4250);
DISPLAY INVISIBLE (-3250 4250);
FORCEPROP 1 LAST BODY_TYPE PLUMBING
J 0
(-3250 4300);
DISPLAY 0.872340 (-3250 4300);
PAINT GREEN (-3250 4300);
DISPLAY INVISIBLE (-3250 4300);
FORCEPROP 1 LAST HDL_TAP TRUE
J 0
(-2925 4125);
DISPLAY 0.872340 (-2925 4125);
DISPLAY INVISIBLE (-2925 4125);
FORCEPROP 1 LAST PATH I197
J 0
(-3252 4250);
DISPLAY 0.872340 (-3252 4250);
PAINT GREEN (-3252 4250);
DISPLAY INVISIBLE (-3252 4250);
FORCEADD TAP..1
(-3250 4150);
FORCEPROP 3 LASTPIN (-3300 4150) SIG_NAME M_B_CPU1_SA_DQS_DN<6>
J 0
(-3290 4160);
DISPLAY 0.659574 (-3290 4160);
PAINT MONO (-3290 4160);
DISPLAY INVISIBLE (-3290 4160);
FORCEPROP 1 LASTPIN (-3300 4150) BN 6
J 0
(-3312 4158);
DISPLAY 0.489362 (-3312 4158);
PAINT GREEN (-3312 4158);
FORCEPROP 2 LAST CDS_LIB mstr_standard
J 0
(-3250 4150);
DISPLAY 0.723404 (-3250 4150);
PAINT MONO (-3250 4150);
DISPLAY INVISIBLE (-3250 4150);
FORCEPROP 1 LAST BODY_TYPE PLUMBING
J 0
(-3250 4200);
DISPLAY 0.872340 (-3250 4200);
PAINT GREEN (-3250 4200);
DISPLAY INVISIBLE (-3250 4200);
FORCEPROP 1 LAST HDL_TAP TRUE
J 0
(-2925 4025);
DISPLAY 0.872340 (-2925 4025);
DISPLAY INVISIBLE (-2925 4025);
FORCEPROP 1 LAST PATH I198
J 0
(-3252 4150);
DISPLAY 0.872340 (-3252 4150);
PAINT GREEN (-3252 4150);
DISPLAY INVISIBLE (-3252 4150);
FORCEADD TAP..1
(-3250 4050);
FORCEPROP 3 LASTPIN (-3300 4050) SIG_NAME M_B_CPU1_SA_DQS_DN<5>
J 0
(-3290 4060);
DISPLAY 0.659574 (-3290 4060);
PAINT MONO (-3290 4060);
DISPLAY INVISIBLE (-3290 4060);
FORCEPROP 1 LASTPIN (-3300 4050) BN 5
J 0
(-3312 4058);
DISPLAY 0.489362 (-3312 4058);
PAINT GREEN (-3312 4058);
FORCEPROP 2 LAST CDS_LIB mstr_standard
J 0
(-3250 4050);
DISPLAY 0.723404 (-3250 4050);
PAINT MONO (-3250 4050);
DISPLAY INVISIBLE (-3250 4050);
FORCEPROP 1 LAST BODY_TYPE PLUMBING
J 0
(-3250 4100);
DISPLAY 0.872340 (-3250 4100);
PAINT GREEN (-3250 4100);
DISPLAY INVISIBLE (-3250 4100);
FORCEPROP 1 LAST HDL_TAP TRUE
J 0
(-2925 3925);
DISPLAY 0.872340 (-2925 3925);
DISPLAY INVISIBLE (-2925 3925);
FORCEPROP 1 LAST PATH I199
J 0
(-3252 4050);
DISPLAY 0.872340 (-3252 4050);
PAINT GREEN (-3252 4050);
DISPLAY INVISIBLE (-3252 4050);
FORCEADD OFFPAGE..1
(-8375 3025);
FORCEPROP 2 LAST $XR0 98 
J 0
(-8626 3025);
DISPLAY 0.638298 (-8626 3025);
PAINT MONO (-8626 3025);
FORCEPROP 2 LAST PATH I2
J 0
(-8625 3075);
DISPLAY 1.021277 (-8625 3075);
DISPLAY INVISIBLE (-8625 3075);
FORCEPROP 1 LAST COMMENT_BODY TRUE
J 0
(-8250 2925);
DISPLAY 0.872340 (-8250 2925);
PAINT GREEN (-8250 2925);
DISPLAY INVISIBLE (-8250 2925);
FORCEPROP 1 LAST OFFPAGE TRUE
J 0
(-8050 2900);
DISPLAY 0.872340 (-8050 2900);
PAINT GREEN (-8050 2900);
DISPLAY INVISIBLE (-8050 2900);
FORCEPROP 2 LAST CDS_LIB mstr_standard
J 0
(-8375 3025);
DISPLAY 0.808511 (-8375 3025);
DISPLAY INVISIBLE (-8375 3025);
FORCEADD OFFPAGE..1
(-8375 5575);
FORCEPROP 2 LAST $XR0 38 
J 0
(-8626 5575);
DISPLAY 0.638298 (-8626 5575);
PAINT MONO (-8626 5575);
FORCEPROP 2 LAST PATH I20
J 0
(-8575 5625);
DISPLAY 1.021277 (-8575 5625);
DISPLAY INVISIBLE (-8575 5625);
FORCEPROP 1 LAST COMMENT_BODY TRUE
J 0
(-8250 5475);
DISPLAY 0.872340 (-8250 5475);
PAINT GREEN (-8250 5475);
DISPLAY INVISIBLE (-8250 5475);
FORCEPROP 1 LAST OFFPAGE TRUE
J 0
(-8050 5450);
DISPLAY 0.872340 (-8050 5450);
PAINT GREEN (-8050 5450);
DISPLAY INVISIBLE (-8050 5450);
FORCEPROP 2 LAST CDS_LIB mstr_standard
J 0
(-8375 5575);
DISPLAY 0.723404 (-8375 5575);
PAINT MONO (-8375 5575);
DISPLAY INVISIBLE (-8375 5575);
FORCEADD TAP..1
(-3450 4400);
FORCEPROP 3 LASTPIN (-3500 4400) SIG_NAME M_B_CPU1_SA_DQS_DP<8>
J 0
(-3490 4410);
DISPLAY 0.659574 (-3490 4410);
PAINT MONO (-3490 4410);
DISPLAY INVISIBLE (-3490 4410);
FORCEPROP 1 LASTPIN (-3500 4400) BN 8
J 0
(-3512 4408);
DISPLAY 0.489362 (-3512 4408);
PAINT GREEN (-3512 4408);
FORCEPROP 2 LAST CDS_LIB mstr_standard
J 0
(-3450 4400);
DISPLAY 0.723404 (-3450 4400);
PAINT MONO (-3450 4400);
DISPLAY INVISIBLE (-3450 4400);
FORCEPROP 1 LAST BODY_TYPE PLUMBING
J 0
(-3450 4450);
DISPLAY 0.872340 (-3450 4450);
PAINT GREEN (-3450 4450);
DISPLAY INVISIBLE (-3450 4450);
FORCEPROP 1 LAST HDL_TAP TRUE
J 0
(-3125 4275);
DISPLAY 0.872340 (-3125 4275);
DISPLAY INVISIBLE (-3125 4275);
FORCEPROP 1 LAST PATH I200
J 0
(-3452 4400);
DISPLAY 0.872340 (-3452 4400);
PAINT GREEN (-3452 4400);
DISPLAY INVISIBLE (-3452 4400);
FORCEADD TAP..1
(-3450 4500);
FORCEPROP 3 LASTPIN (-3500 4500) SIG_NAME M_B_CPU1_SA_DQS_DP<9>
J 0
(-3490 4510);
DISPLAY 0.659574 (-3490 4510);
PAINT MONO (-3490 4510);
DISPLAY INVISIBLE (-3490 4510);
FORCEPROP 1 LASTPIN (-3500 4500) BN 9
J 0
(-3512 4508);
DISPLAY 0.489362 (-3512 4508);
PAINT GREEN (-3512 4508);
FORCEPROP 2 LAST CDS_LIB mstr_standard
J 0
(-3450 4500);
DISPLAY 0.723404 (-3450 4500);
PAINT MONO (-3450 4500);
DISPLAY INVISIBLE (-3450 4500);
FORCEPROP 1 LAST BODY_TYPE PLUMBING
J 0
(-3450 4550);
DISPLAY 0.872340 (-3450 4550);
PAINT GREEN (-3450 4550);
DISPLAY INVISIBLE (-3450 4550);
FORCEPROP 1 LAST HDL_TAP TRUE
J 0
(-3125 4375);
DISPLAY 0.872340 (-3125 4375);
DISPLAY INVISIBLE (-3125 4375);
FORCEPROP 1 LAST PATH I201
J 0
(-3452 4500);
DISPLAY 0.872340 (-3452 4500);
PAINT GREEN (-3452 4500);
DISPLAY INVISIBLE (-3452 4500);
FORCEADD TAP..1
(-3450 4300);
FORCEPROP 3 LASTPIN (-3500 4300) SIG_NAME M_B_CPU1_SA_DQS_DP<7>
J 0
(-3490 4310);
DISPLAY 0.659574 (-3490 4310);
PAINT MONO (-3490 4310);
DISPLAY INVISIBLE (-3490 4310);
FORCEPROP 1 LASTPIN (-3500 4300) BN 7
J 0
(-3512 4308);
DISPLAY 0.489362 (-3512 4308);
PAINT GREEN (-3512 4308);
FORCEPROP 2 LAST CDS_LIB mstr_standard
J 0
(-3450 4300);
DISPLAY 0.723404 (-3450 4300);
PAINT MONO (-3450 4300);
DISPLAY INVISIBLE (-3450 4300);
FORCEPROP 1 LAST BODY_TYPE PLUMBING
J 0
(-3450 4350);
DISPLAY 0.872340 (-3450 4350);
PAINT GREEN (-3450 4350);
DISPLAY INVISIBLE (-3450 4350);
FORCEPROP 1 LAST HDL_TAP TRUE
J 0
(-3125 4175);
DISPLAY 0.872340 (-3125 4175);
DISPLAY INVISIBLE (-3125 4175);
FORCEPROP 1 LAST PATH I202
J 0
(-3452 4300);
DISPLAY 0.872340 (-3452 4300);
PAINT GREEN (-3452 4300);
DISPLAY INVISIBLE (-3452 4300);
FORCEADD TAP..1
(-3450 4100);
FORCEPROP 3 LASTPIN (-3500 4100) SIG_NAME M_B_CPU1_SA_DQS_DP<5>
J 0
(-3490 4110);
DISPLAY 0.659574 (-3490 4110);
PAINT MONO (-3490 4110);
DISPLAY INVISIBLE (-3490 4110);
FORCEPROP 1 LASTPIN (-3500 4100) BN 5
J 0
(-3512 4108);
DISPLAY 0.489362 (-3512 4108);
PAINT GREEN (-3512 4108);
FORCEPROP 2 LAST CDS_LIB mstr_standard
J 0
(-3450 4100);
DISPLAY 0.723404 (-3450 4100);
PAINT MONO (-3450 4100);
DISPLAY INVISIBLE (-3450 4100);
FORCEPROP 1 LAST BODY_TYPE PLUMBING
J 0
(-3450 4150);
DISPLAY 0.872340 (-3450 4150);
PAINT GREEN (-3450 4150);
DISPLAY INVISIBLE (-3450 4150);
FORCEPROP 1 LAST HDL_TAP TRUE
J 0
(-3125 3975);
DISPLAY 0.872340 (-3125 3975);
DISPLAY INVISIBLE (-3125 3975);
FORCEPROP 1 LAST PATH I203
J 0
(-3452 4100);
DISPLAY 0.872340 (-3452 4100);
PAINT GREEN (-3452 4100);
DISPLAY INVISIBLE (-3452 4100);
FORCEADD TAP..1
(-3450 4200);
FORCEPROP 3 LASTPIN (-3500 4200) SIG_NAME M_B_CPU1_SA_DQS_DP<6>
J 0
(-3490 4210);
DISPLAY 0.659574 (-3490 4210);
PAINT MONO (-3490 4210);
DISPLAY INVISIBLE (-3490 4210);
FORCEPROP 1 LASTPIN (-3500 4200) BN 6
J 0
(-3512 4208);
DISPLAY 0.489362 (-3512 4208);
PAINT GREEN (-3512 4208);
FORCEPROP 2 LAST CDS_LIB mstr_standard
J 0
(-3450 4200);
DISPLAY 0.723404 (-3450 4200);
PAINT MONO (-3450 4200);
DISPLAY INVISIBLE (-3450 4200);
FORCEPROP 1 LAST BODY_TYPE PLUMBING
J 0
(-3450 4250);
DISPLAY 0.872340 (-3450 4250);
PAINT GREEN (-3450 4250);
DISPLAY INVISIBLE (-3450 4250);
FORCEPROP 1 LAST HDL_TAP TRUE
J 0
(-3125 4075);
DISPLAY 0.872340 (-3125 4075);
DISPLAY INVISIBLE (-3125 4075);
FORCEPROP 1 LAST PATH I204
J 0
(-3452 4200);
DISPLAY 0.872340 (-3452 4200);
PAINT GREEN (-3452 4200);
DISPLAY INVISIBLE (-3452 4200);
FORCEADD OFFPAGE..2
(-2450 3500);
FORCEPROP 2 LAST $XR0 38 
J 0
(-2261 3500);
DISPLAY 0.638298 (-2261 3500);
PAINT MONO (-2261 3500);
FORCEPROP 1 LAST COMMENT_BODY TRUE
J 0
(-2495 3405);
DISPLAY 0.872340 (-2495 3405);
PAINT GREEN (-2495 3405);
DISPLAY INVISIBLE (-2495 3405);
FORCEPROP 1 LAST OFFPAGE TRUE
J 0
(-2125 3375);
DISPLAY 0.723404 (-2125 3375);
PAINT GREEN (-2125 3375);
DISPLAY INVISIBLE (-2125 3375);
FORCEPROP 2 LAST CDS_LIB mstr_standard
J 0
(-2450 3500);
DISPLAY 0.723404 (-2450 3500);
PAINT MONO (-2450 3500);
DISPLAY INVISIBLE (-2450 3500);
FORCEPROP 2 LAST PATH I205
J 0
(-2250 3550);
DISPLAY 0.680851 (-2250 3550);
DISPLAY INVISIBLE (-2250 3550);
FORCEADD OFFPAGE..2
(-2450 3450);
FORCEPROP 2 LAST $XR0 38 
J 0
(-2261 3450);
DISPLAY 0.638298 (-2261 3450);
PAINT MONO (-2261 3450);
FORCEPROP 1 LAST COMMENT_BODY TRUE
J 0
(-2495 3355);
DISPLAY 0.872340 (-2495 3355);
PAINT GREEN (-2495 3355);
DISPLAY INVISIBLE (-2495 3355);
FORCEPROP 1 LAST OFFPAGE TRUE
J 0
(-2125 3325);
DISPLAY 0.723404 (-2125 3325);
PAINT GREEN (-2125 3325);
DISPLAY INVISIBLE (-2125 3325);
FORCEPROP 2 LAST CDS_LIB mstr_standard
J 0
(-2450 3450);
DISPLAY 0.723404 (-2450 3450);
PAINT MONO (-2450 3450);
DISPLAY INVISIBLE (-2450 3450);
FORCEPROP 2 LAST PATH I206
J 0
(-2250 3500);
DISPLAY 0.680851 (-2250 3500);
DISPLAY INVISIBLE (-2250 3500);
FORCEADD TAP..1
(-3250 3950);
FORCEPROP 3 LASTPIN (-3300 3950) SIG_NAME M_B_CPU1_SA_DQS_DN<4>
J 0
(-3290 3960);
DISPLAY 0.659574 (-3290 3960);
PAINT MONO (-3290 3960);
DISPLAY INVISIBLE (-3290 3960);
FORCEPROP 1 LASTPIN (-3300 3950) BN 4
J 0
(-3312 3958);
DISPLAY 0.489362 (-3312 3958);
PAINT GREEN (-3312 3958);
FORCEPROP 2 LAST CDS_LIB mstr_standard
J 0
(-3250 3950);
DISPLAY 0.723404 (-3250 3950);
PAINT MONO (-3250 3950);
DISPLAY INVISIBLE (-3250 3950);
FORCEPROP 1 LAST BODY_TYPE PLUMBING
J 0
(-3250 4000);
DISPLAY 0.872340 (-3250 4000);
PAINT GREEN (-3250 4000);
DISPLAY INVISIBLE (-3250 4000);
FORCEPROP 1 LAST HDL_TAP TRUE
J 0
(-2925 3825);
DISPLAY 0.872340 (-2925 3825);
DISPLAY INVISIBLE (-2925 3825);
FORCEPROP 1 LAST PATH I207
J 0
(-3252 3950);
DISPLAY 0.872340 (-3252 3950);
PAINT GREEN (-3252 3950);
DISPLAY INVISIBLE (-3252 3950);
FORCEADD TAP..1
(-3250 3850);
FORCEPROP 3 LASTPIN (-3300 3850) SIG_NAME M_B_CPU1_SA_DQS_DN<3>
J 0
(-3290 3860);
DISPLAY 0.659574 (-3290 3860);
PAINT MONO (-3290 3860);
DISPLAY INVISIBLE (-3290 3860);
FORCEPROP 1 LASTPIN (-3300 3850) BN 3
J 0
(-3312 3858);
DISPLAY 0.489362 (-3312 3858);
PAINT GREEN (-3312 3858);
FORCEPROP 2 LAST CDS_LIB mstr_standard
J 0
(-3250 3850);
DISPLAY 0.723404 (-3250 3850);
PAINT MONO (-3250 3850);
DISPLAY INVISIBLE (-3250 3850);
FORCEPROP 1 LAST BODY_TYPE PLUMBING
J 0
(-3250 3900);
DISPLAY 0.872340 (-3250 3900);
PAINT GREEN (-3250 3900);
DISPLAY INVISIBLE (-3250 3900);
FORCEPROP 1 LAST HDL_TAP TRUE
J 0
(-2925 3725);
DISPLAY 0.872340 (-2925 3725);
DISPLAY INVISIBLE (-2925 3725);
FORCEPROP 1 LAST PATH I208
J 0
(-3252 3850);
DISPLAY 0.872340 (-3252 3850);
PAINT GREEN (-3252 3850);
DISPLAY INVISIBLE (-3252 3850);
FORCEADD TAP..1
(-3250 3550);
FORCEPROP 3 LASTPIN (-3300 3550) SIG_NAME M_B_CPU1_SA_DQS_DN<0>
J 0
(-3290 3560);
DISPLAY 0.659574 (-3290 3560);
PAINT MONO (-3290 3560);
DISPLAY INVISIBLE (-3290 3560);
FORCEPROP 1 LASTPIN (-3300 3550) BN 0
J 0
(-3312 3558);
DISPLAY 0.489362 (-3312 3558);
PAINT GREEN (-3312 3558);
FORCEPROP 2 LAST CDS_LIB mstr_standard
J 0
(-3250 3550);
DISPLAY 0.723404 (-3250 3550);
PAINT MONO (-3250 3550);
DISPLAY INVISIBLE (-3250 3550);
FORCEPROP 1 LAST BODY_TYPE PLUMBING
J 0
(-3250 3600);
DISPLAY 0.872340 (-3250 3600);
PAINT GREEN (-3250 3600);
DISPLAY INVISIBLE (-3250 3600);
FORCEPROP 1 LAST HDL_TAP TRUE
J 0
(-2925 3425);
DISPLAY 0.872340 (-2925 3425);
DISPLAY INVISIBLE (-2925 3425);
FORCEPROP 1 LAST PATH I209
J 0
(-3252 3550);
DISPLAY 0.872340 (-3252 3550);
PAINT GREEN (-3252 3550);
DISPLAY INVISIBLE (-3252 3550);
FORCEADD OFFPAGE..1
(-8375 5175);
FORCEPROP 2 LAST $XR0 38 
J 0
(-8626 5175);
DISPLAY 0.638298 (-8626 5175);
PAINT MONO (-8626 5175);
FORCEPROP 2 LAST PATH I21
J 0
(-8575 5225);
DISPLAY 1.021277 (-8575 5225);
DISPLAY INVISIBLE (-8575 5225);
FORCEPROP 1 LAST COMMENT_BODY TRUE
J 0
(-8250 5075);
DISPLAY 0.872340 (-8250 5075);
PAINT GREEN (-8250 5075);
DISPLAY INVISIBLE (-8250 5075);
FORCEPROP 1 LAST OFFPAGE TRUE
J 0
(-8050 5050);
DISPLAY 0.872340 (-8050 5050);
PAINT GREEN (-8050 5050);
DISPLAY INVISIBLE (-8050 5050);
FORCEPROP 2 LAST CDS_LIB mstr_standard
J 0
(-8375 5175);
DISPLAY 0.723404 (-8375 5175);
PAINT MONO (-8375 5175);
DISPLAY INVISIBLE (-8375 5175);
FORCEADD TAP..1
(-3250 3650);
FORCEPROP 3 LASTPIN (-3300 3650) SIG_NAME M_B_CPU1_SA_DQS_DN<1>
J 0
(-3290 3660);
DISPLAY 0.659574 (-3290 3660);
PAINT MONO (-3290 3660);
DISPLAY INVISIBLE (-3290 3660);
FORCEPROP 1 LASTPIN (-3300 3650) BN 1
J 0
(-3312 3658);
DISPLAY 0.489362 (-3312 3658);
PAINT GREEN (-3312 3658);
FORCEPROP 2 LAST CDS_LIB mstr_standard
J 0
(-3250 3650);
DISPLAY 0.723404 (-3250 3650);
PAINT MONO (-3250 3650);
DISPLAY INVISIBLE (-3250 3650);
FORCEPROP 1 LAST BODY_TYPE PLUMBING
J 0
(-3250 3700);
DISPLAY 0.872340 (-3250 3700);
PAINT GREEN (-3250 3700);
DISPLAY INVISIBLE (-3250 3700);
FORCEPROP 1 LAST HDL_TAP TRUE
J 0
(-2925 3525);
DISPLAY 0.872340 (-2925 3525);
DISPLAY INVISIBLE (-2925 3525);
FORCEPROP 1 LAST PATH I210
J 0
(-3252 3650);
DISPLAY 0.872340 (-3252 3650);
PAINT GREEN (-3252 3650);
DISPLAY INVISIBLE (-3252 3650);
FORCEADD TAP..1
(-3250 3300);
FORCEPROP 3 LASTPIN (-3300 3300) SIG_NAME M_B_CPU1_SB_DQS_DN<8>
J 0
(-3290 3310);
DISPLAY 0.659574 (-3290 3310);
PAINT MONO (-3290 3310);
DISPLAY INVISIBLE (-3290 3310);
FORCEPROP 1 LASTPIN (-3300 3300) BN 8
J 0
(-3312 3308);
DISPLAY 0.489362 (-3312 3308);
PAINT GREEN (-3312 3308);
FORCEPROP 2 LAST CDS_LIB mstr_standard
J 0
(-3250 3300);
DISPLAY 0.723404 (-3250 3300);
PAINT MONO (-3250 3300);
DISPLAY INVISIBLE (-3250 3300);
FORCEPROP 1 LAST BODY_TYPE PLUMBING
J 0
(-3250 3350);
DISPLAY 0.872340 (-3250 3350);
PAINT GREEN (-3250 3350);
DISPLAY INVISIBLE (-3250 3350);
FORCEPROP 1 LAST HDL_TAP TRUE
J 0
(-2925 3175);
DISPLAY 0.872340 (-2925 3175);
DISPLAY INVISIBLE (-2925 3175);
FORCEPROP 1 LAST PATH I211
J 0
(-3252 3300);
DISPLAY 0.872340 (-3252 3300);
PAINT GREEN (-3252 3300);
DISPLAY INVISIBLE (-3252 3300);
FORCEADD TAP..1
(-3250 3400);
FORCEPROP 3 LASTPIN (-3300 3400) SIG_NAME M_B_CPU1_SB_DQS_DN<9>
J 0
(-3290 3410);
DISPLAY 0.659574 (-3290 3410);
PAINT MONO (-3290 3410);
DISPLAY INVISIBLE (-3290 3410);
FORCEPROP 1 LASTPIN (-3300 3400) BN 9
J 0
(-3312 3408);
DISPLAY 0.489362 (-3312 3408);
PAINT GREEN (-3312 3408);
FORCEPROP 2 LAST CDS_LIB mstr_standard
J 0
(-3250 3400);
DISPLAY 0.723404 (-3250 3400);
PAINT MONO (-3250 3400);
DISPLAY INVISIBLE (-3250 3400);
FORCEPROP 1 LAST BODY_TYPE PLUMBING
J 0
(-3250 3450);
DISPLAY 0.872340 (-3250 3450);
PAINT GREEN (-3250 3450);
DISPLAY INVISIBLE (-3250 3450);
FORCEPROP 1 LAST HDL_TAP TRUE
J 0
(-2925 3275);
DISPLAY 0.872340 (-2925 3275);
DISPLAY INVISIBLE (-2925 3275);
FORCEPROP 1 LAST PATH I212
J 0
(-3252 3400);
DISPLAY 0.872340 (-3252 3400);
PAINT GREEN (-3252 3400);
DISPLAY INVISIBLE (-3252 3400);
FORCEADD TAP..1
(-3250 3200);
FORCEPROP 3 LASTPIN (-3300 3200) SIG_NAME M_B_CPU1_SB_DQS_DN<7>
J 0
(-3290 3210);
DISPLAY 0.659574 (-3290 3210);
PAINT MONO (-3290 3210);
DISPLAY INVISIBLE (-3290 3210);
FORCEPROP 1 LASTPIN (-3300 3200) BN 7
J 0
(-3312 3208);
DISPLAY 0.489362 (-3312 3208);
PAINT GREEN (-3312 3208);
FORCEPROP 2 LAST CDS_LIB mstr_standard
J 0
(-3250 3200);
DISPLAY 0.723404 (-3250 3200);
PAINT MONO (-3250 3200);
DISPLAY INVISIBLE (-3250 3200);
FORCEPROP 1 LAST BODY_TYPE PLUMBING
J 0
(-3250 3250);
DISPLAY 0.872340 (-3250 3250);
PAINT GREEN (-3250 3250);
DISPLAY INVISIBLE (-3250 3250);
FORCEPROP 1 LAST HDL_TAP TRUE
J 0
(-2925 3075);
DISPLAY 0.872340 (-2925 3075);
DISPLAY INVISIBLE (-2925 3075);
FORCEPROP 1 LAST PATH I213
J 0
(-3252 3200);
DISPLAY 0.872340 (-3252 3200);
PAINT GREEN (-3252 3200);
DISPLAY INVISIBLE (-3252 3200);
FORCEADD TAP..1
(-3250 3100);
FORCEPROP 3 LASTPIN (-3300 3100) SIG_NAME M_B_CPU1_SB_DQS_DN<6>
J 0
(-3290 3110);
DISPLAY 0.659574 (-3290 3110);
PAINT MONO (-3290 3110);
DISPLAY INVISIBLE (-3290 3110);
FORCEPROP 1 LASTPIN (-3300 3100) BN 6
J 0
(-3312 3108);
DISPLAY 0.489362 (-3312 3108);
PAINT GREEN (-3312 3108);
FORCEPROP 2 LAST CDS_LIB mstr_standard
J 0
(-3250 3100);
DISPLAY 0.723404 (-3250 3100);
PAINT MONO (-3250 3100);
DISPLAY INVISIBLE (-3250 3100);
FORCEPROP 1 LAST BODY_TYPE PLUMBING
J 0
(-3250 3150);
DISPLAY 0.872340 (-3250 3150);
PAINT GREEN (-3250 3150);
DISPLAY INVISIBLE (-3250 3150);
FORCEPROP 1 LAST HDL_TAP TRUE
J 0
(-2925 2975);
DISPLAY 0.872340 (-2925 2975);
DISPLAY INVISIBLE (-2925 2975);
FORCEPROP 1 LAST PATH I214
J 0
(-3252 3100);
DISPLAY 0.872340 (-3252 3100);
PAINT GREEN (-3252 3100);
DISPLAY INVISIBLE (-3252 3100);
FORCEADD TAP..1
(-3450 3900);
FORCEPROP 3 LASTPIN (-3500 3900) SIG_NAME M_B_CPU1_SA_DQS_DP<3>
J 0
(-3490 3910);
DISPLAY 0.659574 (-3490 3910);
PAINT MONO (-3490 3910);
DISPLAY INVISIBLE (-3490 3910);
FORCEPROP 1 LASTPIN (-3500 3900) BN 3
J 0
(-3512 3908);
DISPLAY 0.489362 (-3512 3908);
PAINT GREEN (-3512 3908);
FORCEPROP 2 LAST CDS_LIB mstr_standard
J 0
(-3450 3900);
DISPLAY 0.723404 (-3450 3900);
PAINT MONO (-3450 3900);
DISPLAY INVISIBLE (-3450 3900);
FORCEPROP 1 LAST BODY_TYPE PLUMBING
J 0
(-3450 3950);
DISPLAY 0.872340 (-3450 3950);
PAINT GREEN (-3450 3950);
DISPLAY INVISIBLE (-3450 3950);
FORCEPROP 1 LAST HDL_TAP TRUE
J 0
(-3125 3775);
DISPLAY 0.872340 (-3125 3775);
DISPLAY INVISIBLE (-3125 3775);
FORCEPROP 1 LAST PATH I215
J 0
(-3452 3900);
DISPLAY 0.872340 (-3452 3900);
PAINT GREEN (-3452 3900);
DISPLAY INVISIBLE (-3452 3900);
FORCEADD TAP..1
(-3450 4000);
FORCEPROP 3 LASTPIN (-3500 4000) SIG_NAME M_B_CPU1_SA_DQS_DP<4>
J 0
(-3490 4010);
DISPLAY 0.659574 (-3490 4010);
PAINT MONO (-3490 4010);
DISPLAY INVISIBLE (-3490 4010);
FORCEPROP 1 LASTPIN (-3500 4000) BN 4
J 0
(-3512 4008);
DISPLAY 0.489362 (-3512 4008);
PAINT GREEN (-3512 4008);
FORCEPROP 2 LAST CDS_LIB mstr_standard
J 0
(-3450 4000);
DISPLAY 0.723404 (-3450 4000);
PAINT MONO (-3450 4000);
DISPLAY INVISIBLE (-3450 4000);
FORCEPROP 1 LAST BODY_TYPE PLUMBING
J 0
(-3450 4050);
DISPLAY 0.872340 (-3450 4050);
PAINT GREEN (-3450 4050);
DISPLAY INVISIBLE (-3450 4050);
FORCEPROP 1 LAST HDL_TAP TRUE
J 0
(-3125 3875);
DISPLAY 0.872340 (-3125 3875);
DISPLAY INVISIBLE (-3125 3875);
FORCEPROP 1 LAST PATH I216
J 0
(-3452 4000);
DISPLAY 0.872340 (-3452 4000);
PAINT GREEN (-3452 4000);
DISPLAY INVISIBLE (-3452 4000);
FORCEADD TAP..1
(-3450 3800);
FORCEPROP 3 LASTPIN (-3500 3800) SIG_NAME M_B_CPU1_SA_DQS_DP<2>
J 0
(-3490 3810);
DISPLAY 0.659574 (-3490 3810);
PAINT MONO (-3490 3810);
DISPLAY INVISIBLE (-3490 3810);
FORCEPROP 1 LASTPIN (-3500 3800) BN 2
J 0
(-3512 3808);
DISPLAY 0.489362 (-3512 3808);
PAINT GREEN (-3512 3808);
FORCEPROP 2 LAST CDS_LIB mstr_standard
J 0
(-3450 3800);
DISPLAY 0.723404 (-3450 3800);
PAINT MONO (-3450 3800);
DISPLAY INVISIBLE (-3450 3800);
FORCEPROP 1 LAST BODY_TYPE PLUMBING
J 0
(-3450 3850);
DISPLAY 0.872340 (-3450 3850);
PAINT GREEN (-3450 3850);
DISPLAY INVISIBLE (-3450 3850);
FORCEPROP 1 LAST HDL_TAP TRUE
J 0
(-3125 3675);
DISPLAY 0.872340 (-3125 3675);
DISPLAY INVISIBLE (-3125 3675);
FORCEPROP 1 LAST PATH I217
J 0
(-3452 3800);
DISPLAY 0.872340 (-3452 3800);
PAINT GREEN (-3452 3800);
DISPLAY INVISIBLE (-3452 3800);
FORCEADD TAP..1
(-3450 3700);
FORCEPROP 3 LASTPIN (-3500 3700) SIG_NAME M_B_CPU1_SA_DQS_DP<1>
J 0
(-3490 3710);
DISPLAY 0.659574 (-3490 3710);
PAINT MONO (-3490 3710);
DISPLAY INVISIBLE (-3490 3710);
FORCEPROP 1 LASTPIN (-3500 3700) BN 1
J 0
(-3512 3708);
DISPLAY 0.489362 (-3512 3708);
PAINT GREEN (-3512 3708);
FORCEPROP 2 LAST CDS_LIB mstr_standard
J 0
(-3450 3700);
DISPLAY 0.723404 (-3450 3700);
PAINT MONO (-3450 3700);
DISPLAY INVISIBLE (-3450 3700);
FORCEPROP 1 LAST BODY_TYPE PLUMBING
J 0
(-3450 3750);
DISPLAY 0.872340 (-3450 3750);
PAINT GREEN (-3450 3750);
DISPLAY INVISIBLE (-3450 3750);
FORCEPROP 1 LAST HDL_TAP TRUE
J 0
(-3125 3575);
DISPLAY 0.872340 (-3125 3575);
DISPLAY INVISIBLE (-3125 3575);
FORCEPROP 1 LAST PATH I218
J 0
(-3452 3700);
DISPLAY 0.872340 (-3452 3700);
PAINT GREEN (-3452 3700);
DISPLAY INVISIBLE (-3452 3700);
FORCEADD TAP..1
(-3450 3600);
FORCEPROP 3 LASTPIN (-3500 3600) SIG_NAME M_B_CPU1_SA_DQS_DP<0>
J 0
(-3490 3610);
DISPLAY 0.659574 (-3490 3610);
PAINT MONO (-3490 3610);
DISPLAY INVISIBLE (-3490 3610);
FORCEPROP 1 LASTPIN (-3500 3600) BN 0
J 0
(-3512 3608);
DISPLAY 0.489362 (-3512 3608);
PAINT GREEN (-3512 3608);
FORCEPROP 2 LAST CDS_LIB mstr_standard
J 0
(-3450 3600);
DISPLAY 0.723404 (-3450 3600);
PAINT MONO (-3450 3600);
DISPLAY INVISIBLE (-3450 3600);
FORCEPROP 1 LAST BODY_TYPE PLUMBING
J 0
(-3450 3650);
DISPLAY 0.872340 (-3450 3650);
PAINT GREEN (-3450 3650);
DISPLAY INVISIBLE (-3450 3650);
FORCEPROP 1 LAST HDL_TAP TRUE
J 0
(-3125 3475);
DISPLAY 0.872340 (-3125 3475);
DISPLAY INVISIBLE (-3125 3475);
FORCEPROP 1 LAST PATH I219
J 0
(-3452 3600);
DISPLAY 0.872340 (-3452 3600);
PAINT GREEN (-3452 3600);
DISPLAY INVISIBLE (-3452 3600);
FORCEADD SCONN288_DDR506112002KQ..1
(-6925 3775);
FORCEPROP 1 LAST LOCATION J26
J 0
(-7375 5850);
DISPLAY 0.468085 (-7375 5850);
PAINT SKYBLUE (-7375 5850);
FORCEPROP 0 LAST $SEC 1
J 0
(-7375 6000);
DISPLAY 0.680851 (-7375 6000);
PAINT MONO (-7375 6000);
DISPLAY INVISIBLE (-7375 6000);
FORCEPROP 2 LAST CDS_SEC 1
J 0
(-7375 6000);
DISPLAY 1.021277 (-7375 6000);
DISPLAY INVISIBLE (-7375 6000);
FORCEPROP 0 LASTPIN (-7525 3175) $PN 62
J 2
(-7535 3185);
DISPLAY 0.680851 (-7535 3185);
PAINT MONO (-7535 3185);
FORCEPROP 0 LASTPIN (-7525 5225) $PN 66
J 2
(-7535 5235);
DISPLAY 0.680851 (-7535 5235);
PAINT MONO (-7535 5235);
FORCEPROP 0 LASTPIN (-7525 4825) $PN 76
J 2
(-7535 4835);
DISPLAY 0.680851 (-7535 4835);
PAINT MONO (-7535 4835);
FORCEPROP 0 LASTPIN (-7525 5275) $PN 211
J 2
(-7535 5285);
DISPLAY 0.680851 (-7535 5285);
PAINT MONO (-7535 5285);
FORCEPROP 0 LASTPIN (-7525 4875) $PN 221
J 2
(-7535 4885);
DISPLAY 0.680851 (-7535 4885);
PAINT MONO (-7535 4885);
FORCEPROP 0 LASTPIN (-7525 5325) $PN 68
J 2
(-7535 5335);
DISPLAY 0.680851 (-7535 5335);
PAINT MONO (-7535 5335);
FORCEPROP 0 LASTPIN (-7525 4925) $PN 78
J 2
(-7535 4935);
DISPLAY 0.680851 (-7535 4935);
PAINT MONO (-7535 4935);
FORCEPROP 0 LASTPIN (-7525 5375) $PN 213
J 2
(-7535 5385);
DISPLAY 0.680851 (-7535 5385);
PAINT MONO (-7535 5385);
FORCEPROP 0 LASTPIN (-7525 4975) $PN 223
J 2
(-7535 4985);
DISPLAY 0.680851 (-7535 4985);
PAINT MONO (-7535 4985);
FORCEPROP 0 LASTPIN (-7525 5425) $PN 70
J 2
(-7535 5435);
DISPLAY 0.680851 (-7535 5435);
PAINT MONO (-7535 5435);
FORCEPROP 0 LASTPIN (-7525 5025) $PN 80
J 2
(-7535 5035);
DISPLAY 0.680851 (-7535 5035);
PAINT MONO (-7535 5035);
FORCEPROP 0 LASTPIN (-7525 5475) $PN 215
J 2
(-7535 5485);
DISPLAY 0.680851 (-7535 5485);
PAINT MONO (-7535 5485);
FORCEPROP 0 LASTPIN (-7525 5075) $PN 225
J 2
(-7535 5085);
DISPLAY 0.680851 (-7535 5085);
PAINT MONO (-7535 5085);
FORCEPROP 0 LASTPIN (-7525 5525) $PN 72
J 2
(-7535 5535);
DISPLAY 0.680851 (-7535 5535);
PAINT MONO (-7535 5535);
FORCEPROP 0 LASTPIN (-7525 5125) $PN 82
J 2
(-7535 5135);
DISPLAY 0.680851 (-7535 5135);
PAINT MONO (-7535 5135);
FORCEPROP 0 LASTPIN (-7525 3775) $PN 51
J 2
(-7535 3785);
DISPLAY 0.680851 (-7535 3785);
PAINT MONO (-7535 3785);
FORCEPROP 0 LASTPIN (-7525 3325) $PN 96
J 2
(-7535 3335);
DISPLAY 0.680851 (-7535 3335);
PAINT MONO (-7535 3335);
FORCEPROP 0 LASTPIN (-7525 3825) $PN 53
J 2
(-7535 3835);
DISPLAY 0.680851 (-7535 3835);
PAINT MONO (-7535 3835);
FORCEPROP 0 LASTPIN (-7525 3375) $PN 98
J 2
(-7535 3385);
DISPLAY 0.680851 (-7535 3385);
PAINT MONO (-7535 3385);
FORCEPROP 0 LASTPIN (-7525 3875) $PN 196
J 2
(-7535 3885);
DISPLAY 0.680851 (-7535 3885);
PAINT MONO (-7535 3885);
FORCEPROP 0 LASTPIN (-7525 3425) $PN 241
J 2
(-7535 3435);
DISPLAY 0.680851 (-7535 3435);
PAINT MONO (-7535 3435);
FORCEPROP 0 LASTPIN (-7525 3925) $PN 198
J 2
(-7535 3935);
DISPLAY 0.680851 (-7535 3935);
PAINT MONO (-7535 3935);
FORCEPROP 0 LASTPIN (-7525 3475) $PN 243
J 2
(-7535 3485);
DISPLAY 0.680851 (-7535 3485);
PAINT MONO (-7535 3485);
FORCEPROP 0 LASTPIN (-7525 3975) $PN 58
J 2
(-7535 3985);
DISPLAY 0.680851 (-7535 3985);
PAINT MONO (-7535 3985);
FORCEPROP 0 LASTPIN (-7525 3525) $PN 89
J 2
(-7535 3535);
DISPLAY 0.680851 (-7535 3535);
PAINT MONO (-7535 3535);
FORCEPROP 0 LASTPIN (-7525 4025) $PN 60
J 2
(-7535 4035);
DISPLAY 0.680851 (-7535 4035);
PAINT MONO (-7535 4035);
FORCEPROP 0 LASTPIN (-7525 3575) $PN 91
J 2
(-7535 3585);
DISPLAY 0.680851 (-7535 3585);
PAINT MONO (-7535 3585);
FORCEPROP 0 LASTPIN (-7525 4075) $PN 203
J 2
(-7535 4085);
DISPLAY 0.680851 (-7535 4085);
PAINT MONO (-7535 4085);
FORCEPROP 0 LASTPIN (-7525 3625) $PN 234
J 2
(-7535 3635);
DISPLAY 0.680851 (-7535 3635);
PAINT MONO (-7535 3635);
FORCEPROP 0 LASTPIN (-7525 4125) $PN 205
J 2
(-7535 4135);
DISPLAY 0.680851 (-7535 4135);
PAINT MONO (-7535 4135);
FORCEPROP 0 LASTPIN (-7525 3675) $PN 236
J 2
(-7535 3685);
DISPLAY 0.680851 (-7535 3685);
PAINT MONO (-7535 3685);
FORCEPROP 0 LASTPIN (-7525 4225) $PN 218
J 2
(-7535 4235);
DISPLAY 0.680851 (-7535 4235);
PAINT MONO (-7535 4235);
FORCEPROP 0 LASTPIN (-7525 4275) $PN 217
J 2
(-7535 4285);
DISPLAY 0.680851 (-7535 4285);
PAINT MONO (-7535 4285);
FORCEPROP 0 LASTPIN (-7525 4525) $PN 64
J 2
(-7535 4535);
DISPLAY 0.680851 (-7535 4535);
PAINT MONO (-7535 4535);
FORCEPROP 0 LASTPIN (-7525 4375) $PN 84
J 2
(-7535 4385);
DISPLAY 0.680851 (-7535 4385);
PAINT MONO (-7535 4385);
FORCEPROP 0 LASTPIN (-7525 4575) $PN 209
J 2
(-7535 4585);
DISPLAY 0.680851 (-7535 4585);
PAINT MONO (-7535 4585);
FORCEPROP 0 LASTPIN (-7525 4425) $PN 229
J 2
(-7535 4435);
DISPLAY 0.680851 (-7535 4435);
PAINT MONO (-7535 4435);
FORCEPROP 0 LASTPIN (-6325 3975) $PN 7
J 0
(-6315 3985);
DISPLAY 0.680851 (-6315 3985);
PAINT MONO (-6315 3985);
FORCEPROP 0 LASTPIN (-6325 2325) $PN 100
J 0
(-6315 2335);
DISPLAY 0.680851 (-6315 2335);
PAINT MONO (-6315 2335);
FORCEPROP 0 LASTPIN (-6325 4025) $PN 9
J 0
(-6315 4035);
DISPLAY 0.680851 (-6315 4035);
PAINT MONO (-6315 4035);
FORCEPROP 0 LASTPIN (-6325 2375) $PN 102
J 0
(-6315 2385);
DISPLAY 0.680851 (-6315 2385);
PAINT MONO (-6315 2385);
FORCEPROP 0 LASTPIN (-6325 4075) $PN 152
J 0
(-6315 4085);
DISPLAY 0.680851 (-6315 4085);
PAINT MONO (-6315 4085);
FORCEPROP 0 LASTPIN (-6325 2425) $PN 245
J 0
(-6315 2435);
DISPLAY 0.680851 (-6315 2435);
PAINT MONO (-6315 2435);
FORCEPROP 0 LASTPIN (-6325 4125) $PN 154
J 0
(-6315 4135);
DISPLAY 0.680851 (-6315 4135);
PAINT MONO (-6315 4135);
FORCEPROP 0 LASTPIN (-6325 2475) $PN 247
J 0
(-6315 2485);
DISPLAY 0.680851 (-6315 2485);
PAINT MONO (-6315 2485);
FORCEPROP 0 LASTPIN (-6325 4175) $PN 14
J 0
(-6315 4185);
DISPLAY 0.680851 (-6315 4185);
PAINT MONO (-6315 4185);
FORCEPROP 0 LASTPIN (-6325 2525) $PN 107
J 0
(-6315 2535);
DISPLAY 0.680851 (-6315 2535);
PAINT MONO (-6315 2535);
FORCEPROP 0 LASTPIN (-6325 4225) $PN 16
J 0
(-6315 4235);
DISPLAY 0.680851 (-6315 4235);
PAINT MONO (-6315 4235);
FORCEPROP 0 LASTPIN (-6325 2575) $PN 109
J 0
(-6315 2585);
DISPLAY 0.680851 (-6315 2585);
PAINT MONO (-6315 2585);
FORCEPROP 0 LASTPIN (-6325 4275) $PN 159
J 0
(-6315 4285);
DISPLAY 0.680851 (-6315 4285);
PAINT MONO (-6315 4285);
FORCEPROP 0 LASTPIN (-6325 2625) $PN 252
J 0
(-6315 2635);
DISPLAY 0.680851 (-6315 2635);
PAINT MONO (-6315 2635);
FORCEPROP 0 LASTPIN (-6325 4325) $PN 161
J 0
(-6315 4335);
DISPLAY 0.680851 (-6315 4335);
PAINT MONO (-6315 4335);
FORCEPROP 0 LASTPIN (-6325 2675) $PN 254
J 0
(-6315 2685);
DISPLAY 0.680851 (-6315 2685);
PAINT MONO (-6315 2685);
FORCEPROP 0 LASTPIN (-6325 4375) $PN 18
J 0
(-6315 4385);
DISPLAY 0.680851 (-6315 4385);
PAINT MONO (-6315 4385);
FORCEPROP 0 LASTPIN (-6325 2725) $PN 111
J 0
(-6315 2735);
DISPLAY 0.680851 (-6315 2735);
PAINT MONO (-6315 2735);
FORCEPROP 0 LASTPIN (-6325 4425) $PN 20
J 0
(-6315 4435);
DISPLAY 0.680851 (-6315 4435);
PAINT MONO (-6315 4435);
FORCEPROP 0 LASTPIN (-6325 2775) $PN 113
J 0
(-6315 2785);
DISPLAY 0.680851 (-6315 2785);
PAINT MONO (-6315 2785);
FORCEPROP 0 LASTPIN (-6325 4475) $PN 163
J 0
(-6315 4485);
DISPLAY 0.680851 (-6315 4485);
PAINT MONO (-6315 4485);
FORCEPROP 0 LASTPIN (-6325 2825) $PN 256
J 0
(-6315 2835);
DISPLAY 0.680851 (-6315 2835);
PAINT MONO (-6315 2835);
FORCEPROP 0 LASTPIN (-6325 4525) $PN 165
J 0
(-6315 4535);
DISPLAY 0.680851 (-6315 4535);
PAINT MONO (-6315 4535);
FORCEPROP 0 LASTPIN (-6325 2875) $PN 258
J 0
(-6315 2885);
DISPLAY 0.680851 (-6315 2885);
PAINT MONO (-6315 2885);
FORCEPROP 0 LASTPIN (-6325 4575) $PN 25
J 0
(-6315 4585);
DISPLAY 0.680851 (-6315 4585);
PAINT MONO (-6315 4585);
FORCEPROP 0 LASTPIN (-6325 2925) $PN 118
J 0
(-6315 2935);
DISPLAY 0.680851 (-6315 2935);
PAINT MONO (-6315 2935);
FORCEPROP 0 LASTPIN (-6325 4625) $PN 27
J 0
(-6315 4635);
DISPLAY 0.680851 (-6315 4635);
PAINT MONO (-6315 4635);
FORCEPROP 0 LASTPIN (-6325 2975) $PN 120
J 0
(-6315 2985);
DISPLAY 0.680851 (-6315 2985);
PAINT MONO (-6315 2985);
FORCEPROP 0 LASTPIN (-6325 4675) $PN 170
J 0
(-6315 4685);
DISPLAY 0.680851 (-6315 4685);
PAINT MONO (-6315 4685);
FORCEPROP 0 LASTPIN (-6325 3025) $PN 263
J 0
(-6315 3035);
DISPLAY 0.680851 (-6315 3035);
PAINT MONO (-6315 3035);
FORCEPROP 0 LASTPIN (-6325 4725) $PN 172
J 0
(-6315 4735);
DISPLAY 0.680851 (-6315 4735);
PAINT MONO (-6315 4735);
FORCEPROP 0 LASTPIN (-6325 3075) $PN 265
J 0
(-6315 3085);
DISPLAY 0.680851 (-6315 3085);
PAINT MONO (-6315 3085);
FORCEPROP 0 LASTPIN (-6325 4775) $PN 29
J 0
(-6315 4785);
DISPLAY 0.680851 (-6315 4785);
PAINT MONO (-6315 4785);
FORCEPROP 0 LASTPIN (-6325 3125) $PN 122
J 0
(-6315 3135);
DISPLAY 0.680851 (-6315 3135);
PAINT MONO (-6315 3135);
FORCEPROP 0 LASTPIN (-6325 4825) $PN 31
J 0
(-6315 4835);
DISPLAY 0.680851 (-6315 4835);
PAINT MONO (-6315 4835);
FORCEPROP 0 LASTPIN (-6325 3175) $PN 124
J 0
(-6315 3185);
DISPLAY 0.680851 (-6315 3185);
PAINT MONO (-6315 3185);
FORCEPROP 0 LASTPIN (-6325 4875) $PN 174
J 0
(-6315 4885);
DISPLAY 0.680851 (-6315 4885);
PAINT MONO (-6315 4885);
FORCEPROP 0 LASTPIN (-6325 3225) $PN 267
J 0
(-6315 3235);
DISPLAY 0.680851 (-6315 3235);
PAINT MONO (-6315 3235);
FORCEPROP 0 LASTPIN (-6325 4925) $PN 176
J 0
(-6315 4935);
DISPLAY 0.680851 (-6315 4935);
PAINT MONO (-6315 4935);
FORCEPROP 0 LASTPIN (-6325 3275) $PN 269
J 0
(-6315 3285);
DISPLAY 0.680851 (-6315 3285);
PAINT MONO (-6315 3285);
FORCEPROP 0 LASTPIN (-6325 4975) $PN 36
J 0
(-6315 4985);
DISPLAY 0.680851 (-6315 4985);
PAINT MONO (-6315 4985);
FORCEPROP 0 LASTPIN (-6325 3325) $PN 129
J 0
(-6315 3335);
DISPLAY 0.680851 (-6315 3335);
PAINT MONO (-6315 3335);
FORCEPROP 0 LASTPIN (-6325 5025) $PN 38
J 0
(-6315 5035);
DISPLAY 0.680851 (-6315 5035);
PAINT MONO (-6315 5035);
FORCEPROP 0 LASTPIN (-6325 3375) $PN 131
J 0
(-6315 3385);
DISPLAY 0.680851 (-6315 3385);
PAINT MONO (-6315 3385);
FORCEPROP 0 LASTPIN (-6325 5075) $PN 181
J 0
(-6315 5085);
DISPLAY 0.680851 (-6315 5085);
PAINT MONO (-6315 5085);
FORCEPROP 0 LASTPIN (-6325 3425) $PN 274
J 0
(-6315 3435);
DISPLAY 0.680851 (-6315 3435);
PAINT MONO (-6315 3435);
FORCEPROP 0 LASTPIN (-6325 5125) $PN 183
J 0
(-6315 5135);
DISPLAY 0.680851 (-6315 5135);
PAINT MONO (-6315 5135);
FORCEPROP 0 LASTPIN (-6325 3475) $PN 276
J 0
(-6315 3485);
DISPLAY 0.680851 (-6315 3485);
PAINT MONO (-6315 3485);
FORCEPROP 0 LASTPIN (-6325 5175) $PN 40
J 0
(-6315 5185);
DISPLAY 0.680851 (-6315 5185);
PAINT MONO (-6315 5185);
FORCEPROP 0 LASTPIN (-6325 3525) $PN 133
J 0
(-6315 3535);
DISPLAY 0.680851 (-6315 3535);
PAINT MONO (-6315 3535);
FORCEPROP 0 LASTPIN (-6325 5225) $PN 42
J 0
(-6315 5235);
DISPLAY 0.680851 (-6315 5235);
PAINT MONO (-6315 5235);
FORCEPROP 0 LASTPIN (-6325 3575) $PN 135
J 0
(-6315 3585);
DISPLAY 0.680851 (-6315 3585);
PAINT MONO (-6315 3585);
FORCEPROP 0 LASTPIN (-6325 5275) $PN 185
J 0
(-6315 5285);
DISPLAY 0.680851 (-6315 5285);
PAINT MONO (-6315 5285);
FORCEPROP 0 LASTPIN (-6325 3625) $PN 278
J 0
(-6315 3635);
DISPLAY 0.680851 (-6315 3635);
PAINT MONO (-6315 3635);
FORCEPROP 0 LASTPIN (-6325 5325) $PN 187
J 0
(-6315 5335);
DISPLAY 0.680851 (-6315 5335);
PAINT MONO (-6315 5335);
FORCEPROP 0 LASTPIN (-6325 3675) $PN 280
J 0
(-6315 3685);
DISPLAY 0.680851 (-6315 3685);
PAINT MONO (-6315 3685);
FORCEPROP 0 LASTPIN (-6325 5375) $PN 47
J 0
(-6315 5385);
DISPLAY 0.680851 (-6315 5385);
PAINT MONO (-6315 5385);
FORCEPROP 0 LASTPIN (-6325 3725) $PN 140
J 0
(-6315 3735);
DISPLAY 0.680851 (-6315 3735);
PAINT MONO (-6315 3735);
FORCEPROP 0 LASTPIN (-6325 5425) $PN 49
J 0
(-6315 5435);
DISPLAY 0.680851 (-6315 5435);
PAINT MONO (-6315 5435);
FORCEPROP 0 LASTPIN (-6325 3775) $PN 142
J 0
(-6315 3785);
DISPLAY 0.680851 (-6315 3785);
PAINT MONO (-6315 3785);
FORCEPROP 0 LASTPIN (-6325 5475) $PN 192
J 0
(-6315 5485);
DISPLAY 0.680851 (-6315 5485);
PAINT MONO (-6315 5485);
FORCEPROP 0 LASTPIN (-6325 3825) $PN 285
J 0
(-6315 3835);
DISPLAY 0.680851 (-6315 3835);
PAINT MONO (-6315 3835);
FORCEPROP 0 LASTPIN (-6325 5525) $PN 194
J 0
(-6315 5535);
DISPLAY 0.680851 (-6315 5535);
PAINT MONO (-6315 5535);
FORCEPROP 0 LASTPIN (-6325 3875) $PN 287
J 0
(-6315 3885);
DISPLAY 0.680851 (-6315 3885);
PAINT MONO (-6315 3885);
FORCEPROP 0 LASTPIN (-7525 3025) $PN 148
J 2
(-7535 3035);
DISPLAY 0.680851 (-7535 3035);
PAINT MONO (-7535 3035);
FORCEPROP 0 LASTPIN (-7525 2925) $PN 4
J 2
(-7535 2935);
DISPLAY 0.680851 (-7535 2935);
PAINT MONO (-7535 2935);
FORCEPROP 0 LASTPIN (-7525 2975) $PN 5
J 2
(-7535 2985);
DISPLAY 0.680851 (-7535 2985);
PAINT MONO (-7535 2985);
FORCEPROP 0 LASTPIN (-7525 2125) $PN 86
J 2
(-7535 2135);
DISPLAY 0.680851 (-7535 2135);
PAINT MONO (-7535 2135);
FORCEPROP 0 LASTPIN (-7525 2075) $PN 87
J 2
(-7535 2085);
DISPLAY 0.680851 (-7535 2085);
PAINT MONO (-7535 2085);
FORCEPROP 0 LASTPIN (-7525 4725) $PN 74
J 2
(-7535 4735);
DISPLAY 0.680851 (-7535 4735);
PAINT MONO (-7535 4735);
FORCEPROP 0 LASTPIN (-7525 4675) $PN 227
J 2
(-7535 4685);
DISPLAY 0.680851 (-7535 4685);
PAINT MONO (-7535 4685);
FORCEPROP 0 LASTPIN (-7525 2675) $PN 147
J 2
(-7535 2685);
DISPLAY 0.680851 (-7535 2685);
PAINT MONO (-7535 2685);
FORCEPROP 0 LASTPIN (-7525 3225) $PN 207
J 2
(-7535 3235);
DISPLAY 0.680851 (-7535 3235);
PAINT MONO (-7535 3235);
FORCEPROP 0 LASTPIN (-7525 2275) $PN 2
J 2
(-7535 2285);
DISPLAY 0.680851 (-7535 2285);
PAINT MONO (-7535 2285);
FORCEPROP 0 LASTPIN (-7525 2325) $PN 144
J 2
(-7535 2335);
DISPLAY 0.680851 (-7535 2335);
PAINT MONO (-7535 2335);
FORCEPROP 0 LASTPIN (-7525 2375) $PN 149
J 2
(-7535 2385);
DISPLAY 0.680851 (-7535 2385);
PAINT MONO (-7535 2385);
FORCEPROP 0 LASTPIN (-7525 2425) $PN 150
J 2
(-7535 2435);
DISPLAY 0.680851 (-7535 2435);
PAINT MONO (-7535 2435);
FORCEPROP 0 LASTPIN (-7525 2475) $PN 220
J 2
(-7535 2485);
DISPLAY 0.680851 (-7535 2485);
PAINT MONO (-7535 2485);
FORCEPROP 0 LASTPIN (-7525 2525) $PN 231
J 2
(-7535 2535);
DISPLAY 0.680851 (-7535 2535);
PAINT MONO (-7535 2535);
FORCEPROP 0 LASTPIN (-7525 2575) $PN 232
J 2
(-7535 2585);
DISPLAY 0.680851 (-7535 2585);
PAINT MONO (-7535 2585);
FORCEPROP 0 LASTPIN (-7525 3075) $PN 3
J 2
(-7535 3085);
DISPLAY 0.680851 (-7535 3085);
PAINT MONO (-7535 3085);
FORCEPROP 2 LAST PART_TYPE SMLF
J 0
(-7375 5950);
DISPLAY 1.021277 (-7375 5950);
FORCEPROP 2 LAST VALUE SCONN288_DDR506112002KQ
J 0
(-7375 5900);
DISPLAY 0.489362 (-7375 5900);
PAINT SKYBLUE (-7375 5900);
FORCEPROP 1 LAST MATERIAL IO
J 0
(-7375 5700);
DISPLAY 0.468085 (-7375 5700);
PAINT SKYBLUE (-7375 5700);
FORCEPROP 1 LAST PART_NUMBER DFHST8FS479
J 0
(-7375 5775);
DISPLAY 0.468085 (-7375 5775);
PAINT SKYBLUE (-7375 5775);
FORCEPROP 1 LAST CDS_LMAN_SYM_OUTLINE -450,1900,450,-1850
J 0
(-6925 3775);
DISPLAY 0.468085 (-6925 3775);
PAINT GREEN (-6925 3775);
DISPLAY INVISIBLE (-6925 3775);
FORCEPROP 1 LAST PATH I22
J 0
(-6925 3775);
DISPLAY 0.723404 (-6925 3775);
PAINT GREEN (-6925 3775);
DISPLAY INVISIBLE (-6925 3775);
FORCEPROP 1 LAST NEEDS_NO_SIZE TRUE
J 0
(-6925 3775);
DISPLAY 0.723404 (-6925 3775);
PAINT GREEN (-6925 3775);
DISPLAY INVISIBLE (-6925 3775);
FORCEPROP 2 LAST CDS_LIB pure_quanta
J 0
(-6925 3775);
DISPLAY INVISIBLE (-6925 3775);
FORCEADD TAP..1
(-3450 3350);
FORCEPROP 3 LASTPIN (-3500 3350) SIG_NAME M_B_CPU1_SB_DQS_DP<8>
J 0
(-3490 3360);
DISPLAY 0.659574 (-3490 3360);
PAINT MONO (-3490 3360);
DISPLAY INVISIBLE (-3490 3360);
FORCEPROP 1 LASTPIN (-3500 3350) BN 8
J 0
(-3512 3358);
DISPLAY 0.489362 (-3512 3358);
PAINT GREEN (-3512 3358);
FORCEPROP 2 LAST CDS_LIB mstr_standard
J 0
(-3450 3350);
DISPLAY 0.723404 (-3450 3350);
PAINT MONO (-3450 3350);
DISPLAY INVISIBLE (-3450 3350);
FORCEPROP 1 LAST BODY_TYPE PLUMBING
J 0
(-3450 3400);
DISPLAY 0.872340 (-3450 3400);
PAINT GREEN (-3450 3400);
DISPLAY INVISIBLE (-3450 3400);
FORCEPROP 1 LAST HDL_TAP TRUE
J 0
(-3125 3225);
DISPLAY 0.872340 (-3125 3225);
DISPLAY INVISIBLE (-3125 3225);
FORCEPROP 1 LAST PATH I220
J 0
(-3452 3350);
DISPLAY 0.872340 (-3452 3350);
PAINT GREEN (-3452 3350);
DISPLAY INVISIBLE (-3452 3350);
FORCEADD TAP..1
(-3450 3450);
FORCEPROP 3 LASTPIN (-3500 3450) SIG_NAME M_B_CPU1_SB_DQS_DP<9>
J 0
(-3490 3460);
DISPLAY 0.659574 (-3490 3460);
PAINT MONO (-3490 3460);
DISPLAY INVISIBLE (-3490 3460);
FORCEPROP 1 LASTPIN (-3500 3450) BN 9
J 0
(-3512 3458);
DISPLAY 0.489362 (-3512 3458);
PAINT GREEN (-3512 3458);
FORCEPROP 2 LAST CDS_LIB mstr_standard
J 0
(-3450 3450);
DISPLAY 0.723404 (-3450 3450);
PAINT MONO (-3450 3450);
DISPLAY INVISIBLE (-3450 3450);
FORCEPROP 1 LAST BODY_TYPE PLUMBING
J 0
(-3450 3500);
DISPLAY 0.872340 (-3450 3500);
PAINT GREEN (-3450 3500);
DISPLAY INVISIBLE (-3450 3500);
FORCEPROP 1 LAST HDL_TAP TRUE
J 0
(-3125 3325);
DISPLAY 0.872340 (-3125 3325);
DISPLAY INVISIBLE (-3125 3325);
FORCEPROP 1 LAST PATH I221
J 0
(-3452 3450);
DISPLAY 0.872340 (-3452 3450);
PAINT GREEN (-3452 3450);
DISPLAY INVISIBLE (-3452 3450);
FORCEADD TAP..1
(-3450 3250);
FORCEPROP 3 LASTPIN (-3500 3250) SIG_NAME M_B_CPU1_SB_DQS_DP<7>
J 0
(-3490 3260);
DISPLAY 0.659574 (-3490 3260);
PAINT MONO (-3490 3260);
DISPLAY INVISIBLE (-3490 3260);
FORCEPROP 1 LASTPIN (-3500 3250) BN 7
J 0
(-3512 3258);
DISPLAY 0.489362 (-3512 3258);
PAINT GREEN (-3512 3258);
FORCEPROP 2 LAST CDS_LIB mstr_standard
J 0
(-3450 3250);
DISPLAY 0.723404 (-3450 3250);
PAINT MONO (-3450 3250);
DISPLAY INVISIBLE (-3450 3250);
FORCEPROP 1 LAST BODY_TYPE PLUMBING
J 0
(-3450 3300);
DISPLAY 0.872340 (-3450 3300);
PAINT GREEN (-3450 3300);
DISPLAY INVISIBLE (-3450 3300);
FORCEPROP 1 LAST HDL_TAP TRUE
J 0
(-3125 3125);
DISPLAY 0.872340 (-3125 3125);
DISPLAY INVISIBLE (-3125 3125);
FORCEPROP 1 LAST PATH I222
J 0
(-3452 3250);
DISPLAY 0.872340 (-3452 3250);
PAINT GREEN (-3452 3250);
DISPLAY INVISIBLE (-3452 3250);
FORCEADD TAP..1
(-3450 3150);
FORCEPROP 3 LASTPIN (-3500 3150) SIG_NAME M_B_CPU1_SB_DQS_DP<6>
J 0
(-3490 3160);
DISPLAY 0.659574 (-3490 3160);
PAINT MONO (-3490 3160);
DISPLAY INVISIBLE (-3490 3160);
FORCEPROP 1 LASTPIN (-3500 3150) BN 6
J 0
(-3512 3158);
DISPLAY 0.489362 (-3512 3158);
PAINT GREEN (-3512 3158);
FORCEPROP 2 LAST CDS_LIB mstr_standard
J 0
(-3450 3150);
DISPLAY 0.723404 (-3450 3150);
PAINT MONO (-3450 3150);
DISPLAY INVISIBLE (-3450 3150);
FORCEPROP 1 LAST BODY_TYPE PLUMBING
J 0
(-3450 3200);
DISPLAY 0.872340 (-3450 3200);
PAINT GREEN (-3450 3200);
DISPLAY INVISIBLE (-3450 3200);
FORCEPROP 1 LAST HDL_TAP TRUE
J 0
(-3125 3025);
DISPLAY 0.872340 (-3125 3025);
DISPLAY INVISIBLE (-3125 3025);
FORCEPROP 1 LAST PATH I223
J 0
(-3452 3150);
DISPLAY 0.872340 (-3452 3150);
PAINT GREEN (-3452 3150);
DISPLAY INVISIBLE (-3452 3150);
FORCEADD TAP..1
(-3450 3050);
FORCEPROP 3 LASTPIN (-3500 3050) SIG_NAME M_B_CPU1_SB_DQS_DP<5>
J 0
(-3490 3060);
DISPLAY 0.659574 (-3490 3060);
PAINT MONO (-3490 3060);
DISPLAY INVISIBLE (-3490 3060);
FORCEPROP 1 LASTPIN (-3500 3050) BN 5
J 0
(-3512 3058);
DISPLAY 0.489362 (-3512 3058);
PAINT GREEN (-3512 3058);
FORCEPROP 2 LAST CDS_LIB mstr_standard
J 0
(-3450 3050);
DISPLAY 0.723404 (-3450 3050);
PAINT MONO (-3450 3050);
DISPLAY INVISIBLE (-3450 3050);
FORCEPROP 1 LAST BODY_TYPE PLUMBING
J 0
(-3450 3100);
DISPLAY 0.872340 (-3450 3100);
PAINT GREEN (-3450 3100);
DISPLAY INVISIBLE (-3450 3100);
FORCEPROP 1 LAST HDL_TAP TRUE
J 0
(-3125 2925);
DISPLAY 0.872340 (-3125 2925);
DISPLAY INVISIBLE (-3125 2925);
FORCEPROP 1 LAST PATH I224
J 0
(-3452 3050);
DISPLAY 0.872340 (-3452 3050);
PAINT GREEN (-3452 3050);
DISPLAY INVISIBLE (-3452 3050);
FORCEADD TAP..1
(-3250 3000);
FORCEPROP 3 LASTPIN (-3300 3000) SIG_NAME M_B_CPU1_SB_DQS_DN<5>
J 0
(-3290 3010);
DISPLAY 0.659574 (-3290 3010);
PAINT MONO (-3290 3010);
DISPLAY INVISIBLE (-3290 3010);
FORCEPROP 1 LASTPIN (-3300 3000) BN 5
J 0
(-3312 3008);
DISPLAY 0.489362 (-3312 3008);
PAINT GREEN (-3312 3008);
FORCEPROP 2 LAST CDS_LIB mstr_standard
J 0
(-3250 3000);
DISPLAY 0.723404 (-3250 3000);
PAINT MONO (-3250 3000);
DISPLAY INVISIBLE (-3250 3000);
FORCEPROP 1 LAST BODY_TYPE PLUMBING
J 0
(-3250 3050);
DISPLAY 0.872340 (-3250 3050);
PAINT GREEN (-3250 3050);
DISPLAY INVISIBLE (-3250 3050);
FORCEPROP 1 LAST HDL_TAP TRUE
J 0
(-2925 2875);
DISPLAY 0.872340 (-2925 2875);
DISPLAY INVISIBLE (-2925 2875);
FORCEPROP 1 LAST PATH I225
J 0
(-3252 3000);
DISPLAY 0.872340 (-3252 3000);
PAINT GREEN (-3252 3000);
DISPLAY INVISIBLE (-3252 3000);
FORCEADD TAP..1
(-3250 2900);
FORCEPROP 3 LASTPIN (-3300 2900) SIG_NAME M_B_CPU1_SB_DQS_DN<4>
J 0
(-3290 2910);
DISPLAY 0.659574 (-3290 2910);
PAINT MONO (-3290 2910);
DISPLAY INVISIBLE (-3290 2910);
FORCEPROP 1 LASTPIN (-3300 2900) BN 4
J 0
(-3312 2908);
DISPLAY 0.489362 (-3312 2908);
PAINT GREEN (-3312 2908);
FORCEPROP 2 LAST CDS_LIB mstr_standard
J 0
(-3250 2900);
DISPLAY 0.723404 (-3250 2900);
PAINT MONO (-3250 2900);
DISPLAY INVISIBLE (-3250 2900);
FORCEPROP 1 LAST BODY_TYPE PLUMBING
J 0
(-3250 2950);
DISPLAY 0.872340 (-3250 2950);
PAINT GREEN (-3250 2950);
DISPLAY INVISIBLE (-3250 2950);
FORCEPROP 1 LAST HDL_TAP TRUE
J 0
(-2925 2775);
DISPLAY 0.872340 (-2925 2775);
DISPLAY INVISIBLE (-2925 2775);
FORCEPROP 1 LAST PATH I226
J 0
(-3252 2900);
DISPLAY 0.872340 (-3252 2900);
PAINT GREEN (-3252 2900);
DISPLAY INVISIBLE (-3252 2900);
FORCEADD TAP..1
(-3250 2800);
FORCEPROP 3 LASTPIN (-3300 2800) SIG_NAME M_B_CPU1_SB_DQS_DN<3>
J 0
(-3290 2810);
DISPLAY 0.659574 (-3290 2810);
PAINT MONO (-3290 2810);
DISPLAY INVISIBLE (-3290 2810);
FORCEPROP 1 LASTPIN (-3300 2800) BN 3
J 0
(-3312 2808);
DISPLAY 0.489362 (-3312 2808);
PAINT GREEN (-3312 2808);
FORCEPROP 2 LAST CDS_LIB mstr_standard
J 0
(-3250 2800);
DISPLAY 0.723404 (-3250 2800);
PAINT MONO (-3250 2800);
DISPLAY INVISIBLE (-3250 2800);
FORCEPROP 1 LAST BODY_TYPE PLUMBING
J 0
(-3250 2850);
DISPLAY 0.872340 (-3250 2850);
PAINT GREEN (-3250 2850);
DISPLAY INVISIBLE (-3250 2850);
FORCEPROP 1 LAST HDL_TAP TRUE
J 0
(-2925 2675);
DISPLAY 0.872340 (-2925 2675);
DISPLAY INVISIBLE (-2925 2675);
FORCEPROP 1 LAST PATH I227
J 0
(-3252 2800);
DISPLAY 0.872340 (-3252 2800);
PAINT GREEN (-3252 2800);
DISPLAY INVISIBLE (-3252 2800);
FORCEADD TAP..1
(-3250 2700);
FORCEPROP 3 LASTPIN (-3300 2700) SIG_NAME M_B_CPU1_SB_DQS_DN<2>
J 0
(-3290 2710);
DISPLAY 0.659574 (-3290 2710);
PAINT MONO (-3290 2710);
DISPLAY INVISIBLE (-3290 2710);
FORCEPROP 1 LASTPIN (-3300 2700) BN 2
J 0
(-3312 2708);
DISPLAY 0.489362 (-3312 2708);
PAINT GREEN (-3312 2708);
FORCEPROP 2 LAST CDS_LIB mstr_standard
J 0
(-3250 2700);
DISPLAY 0.723404 (-3250 2700);
PAINT MONO (-3250 2700);
DISPLAY INVISIBLE (-3250 2700);
FORCEPROP 1 LAST BODY_TYPE PLUMBING
J 0
(-3250 2750);
DISPLAY 0.872340 (-3250 2750);
PAINT GREEN (-3250 2750);
DISPLAY INVISIBLE (-3250 2750);
FORCEPROP 1 LAST HDL_TAP TRUE
J 0
(-2925 2575);
DISPLAY 0.872340 (-2925 2575);
DISPLAY INVISIBLE (-2925 2575);
FORCEPROP 1 LAST PATH I228
J 0
(-3252 2700);
DISPLAY 0.872340 (-3252 2700);
PAINT GREEN (-3252 2700);
DISPLAY INVISIBLE (-3252 2700);
FORCEADD TAP..1
(-3250 2600);
FORCEPROP 3 LASTPIN (-3300 2600) SIG_NAME M_B_CPU1_SB_DQS_DN<1>
J 0
(-3290 2610);
DISPLAY 0.659574 (-3290 2610);
PAINT MONO (-3290 2610);
DISPLAY INVISIBLE (-3290 2610);
FORCEPROP 1 LASTPIN (-3300 2600) BN 1
J 0
(-3312 2608);
DISPLAY 0.489362 (-3312 2608);
PAINT GREEN (-3312 2608);
FORCEPROP 2 LAST CDS_LIB mstr_standard
J 0
(-3250 2600);
DISPLAY 0.723404 (-3250 2600);
PAINT MONO (-3250 2600);
DISPLAY INVISIBLE (-3250 2600);
FORCEPROP 1 LAST BODY_TYPE PLUMBING
J 0
(-3250 2650);
DISPLAY 0.872340 (-3250 2650);
PAINT GREEN (-3250 2650);
DISPLAY INVISIBLE (-3250 2650);
FORCEPROP 1 LAST HDL_TAP TRUE
J 0
(-2925 2475);
DISPLAY 0.872340 (-2925 2475);
DISPLAY INVISIBLE (-2925 2475);
FORCEPROP 1 LAST PATH I229
J 0
(-3252 2600);
DISPLAY 0.872340 (-3252 2600);
PAINT GREEN (-3252 2600);
DISPLAY INVISIBLE (-3252 2600);
FORCEADD TAP..1
R 2
(-7775 3325);
FORCEPROP 3 LASTPIN (-7725 3325) SIG_NAME M_B_CPU1_SB_CB<0>
J 0
(-7715 3335);
DISPLAY 0.659574 (-7715 3335);
PAINT MONO (-7715 3335);
DISPLAY INVISIBLE (-7715 3335);
FORCEPROP 1 LASTPIN (-7725 3325) BN 0
J 2
(-7713 3333);
DISPLAY 0.489362 (-7713 3333);
PAINT GREEN (-7713 3333);
FORCEPROP 2 LAST CDS_LIB mstr_standard
J 0
(-7775 3325);
DISPLAY 0.723404 (-7775 3325);
PAINT MONO (-7775 3325);
DISPLAY INVISIBLE (-7775 3325);
FORCEPROP 1 LAST BODY_TYPE PLUMBING
J 2
(-7775 3375);
DISPLAY 0.872340 (-7775 3375);
PAINT GREEN (-7775 3375);
DISPLAY INVISIBLE (-7775 3375);
FORCEPROP 1 LAST HDL_TAP TRUE
J 2
(-8100 3200);
DISPLAY 0.872340 (-8100 3200);
DISPLAY INVISIBLE (-8100 3200);
FORCEPROP 1 LAST PATH I23
J 2
(-7773 3325);
DISPLAY 0.872340 (-7773 3325);
PAINT GREEN (-7773 3325);
DISPLAY INVISIBLE (-7773 3325);
FORCEADD TAP..1
(-3250 2500);
FORCEPROP 3 LASTPIN (-3300 2500) SIG_NAME M_B_CPU1_SB_DQS_DN<0>
J 0
(-3290 2510);
DISPLAY 0.659574 (-3290 2510);
PAINT MONO (-3290 2510);
DISPLAY INVISIBLE (-3290 2510);
FORCEPROP 1 LASTPIN (-3300 2500) BN 0
J 0
(-3312 2508);
DISPLAY 0.489362 (-3312 2508);
PAINT GREEN (-3312 2508);
FORCEPROP 2 LAST CDS_LIB mstr_standard
J 0
(-3250 2500);
DISPLAY 0.723404 (-3250 2500);
PAINT MONO (-3250 2500);
DISPLAY INVISIBLE (-3250 2500);
FORCEPROP 1 LAST BODY_TYPE PLUMBING
J 0
(-3250 2550);
DISPLAY 0.872340 (-3250 2550);
PAINT GREEN (-3250 2550);
DISPLAY INVISIBLE (-3250 2550);
FORCEPROP 1 LAST HDL_TAP TRUE
J 0
(-2925 2375);
DISPLAY 0.872340 (-2925 2375);
DISPLAY INVISIBLE (-2925 2375);
FORCEPROP 1 LAST PATH I230
J 0
(-3252 2500);
DISPLAY 0.872340 (-3252 2500);
PAINT GREEN (-3252 2500);
DISPLAY INVISIBLE (-3252 2500);
FORCEADD TAP..1
(-3450 2850);
FORCEPROP 3 LASTPIN (-3500 2850) SIG_NAME M_B_CPU1_SB_DQS_DP<3>
J 0
(-3490 2860);
DISPLAY 0.659574 (-3490 2860);
PAINT MONO (-3490 2860);
DISPLAY INVISIBLE (-3490 2860);
FORCEPROP 1 LASTPIN (-3500 2850) BN 3
J 0
(-3512 2858);
DISPLAY 0.489362 (-3512 2858);
PAINT GREEN (-3512 2858);
FORCEPROP 2 LAST CDS_LIB mstr_standard
J 0
(-3450 2850);
DISPLAY 0.723404 (-3450 2850);
PAINT MONO (-3450 2850);
DISPLAY INVISIBLE (-3450 2850);
FORCEPROP 1 LAST BODY_TYPE PLUMBING
J 0
(-3450 2900);
DISPLAY 0.872340 (-3450 2900);
PAINT GREEN (-3450 2900);
DISPLAY INVISIBLE (-3450 2900);
FORCEPROP 1 LAST HDL_TAP TRUE
J 0
(-3125 2725);
DISPLAY 0.872340 (-3125 2725);
DISPLAY INVISIBLE (-3125 2725);
FORCEPROP 1 LAST PATH I231
J 0
(-3452 2850);
DISPLAY 0.872340 (-3452 2850);
PAINT GREEN (-3452 2850);
DISPLAY INVISIBLE (-3452 2850);
FORCEADD TAP..1
(-3450 2950);
FORCEPROP 3 LASTPIN (-3500 2950) SIG_NAME M_B_CPU1_SB_DQS_DP<4>
J 0
(-3490 2960);
DISPLAY 0.659574 (-3490 2960);
PAINT MONO (-3490 2960);
DISPLAY INVISIBLE (-3490 2960);
FORCEPROP 1 LASTPIN (-3500 2950) BN 4
J 0
(-3512 2958);
DISPLAY 0.489362 (-3512 2958);
PAINT GREEN (-3512 2958);
FORCEPROP 2 LAST CDS_LIB mstr_standard
J 0
(-3450 2950);
DISPLAY 0.723404 (-3450 2950);
PAINT MONO (-3450 2950);
DISPLAY INVISIBLE (-3450 2950);
FORCEPROP 1 LAST BODY_TYPE PLUMBING
J 0
(-3450 3000);
DISPLAY 0.872340 (-3450 3000);
PAINT GREEN (-3450 3000);
DISPLAY INVISIBLE (-3450 3000);
FORCEPROP 1 LAST HDL_TAP TRUE
J 0
(-3125 2825);
DISPLAY 0.872340 (-3125 2825);
DISPLAY INVISIBLE (-3125 2825);
FORCEPROP 1 LAST PATH I232
J 0
(-3452 2950);
DISPLAY 0.872340 (-3452 2950);
PAINT GREEN (-3452 2950);
DISPLAY INVISIBLE (-3452 2950);
FORCEADD TAP..1
(-3450 2750);
FORCEPROP 3 LASTPIN (-3500 2750) SIG_NAME M_B_CPU1_SB_DQS_DP<2>
J 0
(-3490 2760);
DISPLAY 0.659574 (-3490 2760);
PAINT MONO (-3490 2760);
DISPLAY INVISIBLE (-3490 2760);
FORCEPROP 1 LASTPIN (-3500 2750) BN 2
J 0
(-3512 2758);
DISPLAY 0.489362 (-3512 2758);
PAINT GREEN (-3512 2758);
FORCEPROP 2 LAST CDS_LIB mstr_standard
J 0
(-3450 2750);
DISPLAY 0.723404 (-3450 2750);
PAINT MONO (-3450 2750);
DISPLAY INVISIBLE (-3450 2750);
FORCEPROP 1 LAST BODY_TYPE PLUMBING
J 0
(-3450 2800);
DISPLAY 0.872340 (-3450 2800);
PAINT GREEN (-3450 2800);
DISPLAY INVISIBLE (-3450 2800);
FORCEPROP 1 LAST HDL_TAP TRUE
J 0
(-3125 2625);
DISPLAY 0.872340 (-3125 2625);
DISPLAY INVISIBLE (-3125 2625);
FORCEPROP 1 LAST PATH I233
J 0
(-3452 2750);
DISPLAY 0.872340 (-3452 2750);
PAINT GREEN (-3452 2750);
DISPLAY INVISIBLE (-3452 2750);
FORCEADD TAP..1
(-3450 2550);
FORCEPROP 3 LASTPIN (-3500 2550) SIG_NAME M_B_CPU1_SB_DQS_DP<0>
J 0
(-3490 2560);
DISPLAY 0.659574 (-3490 2560);
PAINT MONO (-3490 2560);
DISPLAY INVISIBLE (-3490 2560);
FORCEPROP 1 LASTPIN (-3500 2550) BN 0
J 0
(-3512 2558);
DISPLAY 0.489362 (-3512 2558);
PAINT GREEN (-3512 2558);
FORCEPROP 2 LAST CDS_LIB mstr_standard
J 0
(-3450 2550);
DISPLAY 0.723404 (-3450 2550);
PAINT MONO (-3450 2550);
DISPLAY INVISIBLE (-3450 2550);
FORCEPROP 1 LAST BODY_TYPE PLUMBING
J 0
(-3450 2600);
DISPLAY 0.872340 (-3450 2600);
PAINT GREEN (-3450 2600);
DISPLAY INVISIBLE (-3450 2600);
FORCEPROP 1 LAST HDL_TAP TRUE
J 0
(-3125 2425);
DISPLAY 0.872340 (-3125 2425);
DISPLAY INVISIBLE (-3125 2425);
FORCEPROP 1 LAST PATH I234
J 0
(-3452 2550);
DISPLAY 0.872340 (-3452 2550);
PAINT GREEN (-3452 2550);
DISPLAY INVISIBLE (-3452 2550);
FORCEADD TAP..1
(-3450 2650);
FORCEPROP 3 LASTPIN (-3500 2650) SIG_NAME M_B_CPU1_SB_DQS_DP<1>
J 0
(-3490 2660);
DISPLAY 0.659574 (-3490 2660);
PAINT MONO (-3490 2660);
DISPLAY INVISIBLE (-3490 2660);
FORCEPROP 1 LASTPIN (-3500 2650) BN 1
J 0
(-3512 2658);
DISPLAY 0.489362 (-3512 2658);
PAINT GREEN (-3512 2658);
FORCEPROP 2 LAST CDS_LIB mstr_standard
J 0
(-3450 2650);
DISPLAY 0.723404 (-3450 2650);
PAINT MONO (-3450 2650);
DISPLAY INVISIBLE (-3450 2650);
FORCEPROP 1 LAST BODY_TYPE PLUMBING
J 0
(-3450 2700);
DISPLAY 0.872340 (-3450 2700);
PAINT GREEN (-3450 2700);
DISPLAY INVISIBLE (-3450 2700);
FORCEPROP 1 LAST HDL_TAP TRUE
J 0
(-3125 2525);
DISPLAY 0.872340 (-3125 2525);
DISPLAY INVISIBLE (-3125 2525);
FORCEPROP 1 LAST PATH I235
J 0
(-3452 2650);
DISPLAY 0.872340 (-3452 2650);
PAINT GREEN (-3452 2650);
DISPLAY INVISIBLE (-3452 2650);
FORCEADD SCONN288_DDR506112002KQ..2
(-4400 3500);
FORCEPROP 1 LAST LOCATION J26
J 0
(-5000 4825);
DISPLAY 0.468085 (-5000 4825);
PAINT SKYBLUE (-5000 4825);
FORCEPROP 0 LAST $SEC 2
J 0
(-4850 4975);
DISPLAY 0.680851 (-4850 4975);
PAINT MONO (-4850 4975);
DISPLAY INVISIBLE (-4850 4975);
FORCEPROP 0 LAST CDS_SEC 2
J 0
(-4850 4975);
DISPLAY 1.021277 (-4850 4975);
DISPLAY INVISIBLE (-4850 4975);
FORCEPROP 0 LASTPIN (-3650 3550) $PN 12
J 0
(-3640 3560);
DISPLAY 0.680851 (-3640 3560);
PAINT MONO (-3640 3560);
FORCEPROP 0 LASTPIN (-3650 3600) $PN 11
J 0
(-3640 3610);
DISPLAY 0.680851 (-3640 3610);
PAINT MONO (-3640 3610);
FORCEPROP 0 LASTPIN (-3650 2500) $PN 105
J 0
(-3640 2510);
DISPLAY 0.680851 (-3640 2510);
PAINT MONO (-3640 2510);
FORCEPROP 0 LASTPIN (-3650 2550) $PN 104
J 0
(-3640 2560);
DISPLAY 0.680851 (-3640 2560);
PAINT MONO (-3640 2560);
FORCEPROP 0 LASTPIN (-3650 3650) $PN 23
J 0
(-3640 3660);
DISPLAY 0.680851 (-3640 3660);
PAINT MONO (-3640 3660);
FORCEPROP 0 LASTPIN (-3650 3700) $PN 22
J 0
(-3640 3710);
DISPLAY 0.680851 (-3640 3710);
PAINT MONO (-3640 3710);
FORCEPROP 0 LASTPIN (-3650 2600) $PN 116
J 0
(-3640 2610);
DISPLAY 0.680851 (-3640 2610);
PAINT MONO (-3640 2610);
FORCEPROP 0 LASTPIN (-3650 2650) $PN 115
J 0
(-3640 2660);
DISPLAY 0.680851 (-3640 2660);
PAINT MONO (-3640 2660);
FORCEPROP 0 LASTPIN (-3650 3750) $PN 34
J 0
(-3640 3760);
DISPLAY 0.680851 (-3640 3760);
PAINT MONO (-3640 3760);
FORCEPROP 0 LASTPIN (-3650 3800) $PN 33
J 0
(-3640 3810);
DISPLAY 0.680851 (-3640 3810);
PAINT MONO (-3640 3810);
FORCEPROP 0 LASTPIN (-3650 2700) $PN 127
J 0
(-3640 2710);
DISPLAY 0.680851 (-3640 2710);
PAINT MONO (-3640 2710);
FORCEPROP 0 LASTPIN (-3650 2750) $PN 126
J 0
(-3640 2760);
DISPLAY 0.680851 (-3640 2760);
PAINT MONO (-3640 2760);
FORCEPROP 0 LASTPIN (-3650 3850) $PN 45
J 0
(-3640 3860);
DISPLAY 0.680851 (-3640 3860);
PAINT MONO (-3640 3860);
FORCEPROP 0 LASTPIN (-3650 3900) $PN 44
J 0
(-3640 3910);
DISPLAY 0.680851 (-3640 3910);
PAINT MONO (-3640 3910);
FORCEPROP 0 LASTPIN (-3650 2800) $PN 138
J 0
(-3640 2810);
DISPLAY 0.680851 (-3640 2810);
PAINT MONO (-3640 2810);
FORCEPROP 0 LASTPIN (-3650 2850) $PN 137
J 0
(-3640 2860);
DISPLAY 0.680851 (-3640 2860);
PAINT MONO (-3640 2860);
FORCEPROP 0 LASTPIN (-3650 3950) $PN 56
J 0
(-3640 3960);
DISPLAY 0.680851 (-3640 3960);
PAINT MONO (-3640 3960);
FORCEPROP 0 LASTPIN (-3650 4000) $PN 55
J 0
(-3640 4010);
DISPLAY 0.680851 (-3640 4010);
PAINT MONO (-3640 4010);
FORCEPROP 0 LASTPIN (-3650 2900) $PN 238
J 0
(-3640 2910);
DISPLAY 0.680851 (-3640 2910);
PAINT MONO (-3640 2910);
FORCEPROP 0 LASTPIN (-3650 2950) $PN 239
J 0
(-3640 2960);
DISPLAY 0.680851 (-3640 2960);
PAINT MONO (-3640 2960);
FORCEPROP 0 LASTPIN (-3650 4050) $PN 156
J 0
(-3640 4060);
DISPLAY 0.680851 (-3640 4060);
PAINT MONO (-3640 4060);
FORCEPROP 0 LASTPIN (-3650 4100) $PN 157
J 0
(-3640 4110);
DISPLAY 0.680851 (-3640 4110);
PAINT MONO (-3640 4110);
FORCEPROP 0 LASTPIN (-3650 3000) $PN 249
J 0
(-3640 3010);
DISPLAY 0.680851 (-3640 3010);
PAINT MONO (-3640 3010);
FORCEPROP 0 LASTPIN (-3650 3050) $PN 250
J 0
(-3640 3060);
DISPLAY 0.680851 (-3640 3060);
PAINT MONO (-3640 3060);
FORCEPROP 0 LASTPIN (-3650 4150) $PN 167
J 0
(-3640 4160);
DISPLAY 0.680851 (-3640 4160);
PAINT MONO (-3640 4160);
FORCEPROP 0 LASTPIN (-3650 4200) $PN 168
J 0
(-3640 4210);
DISPLAY 0.680851 (-3640 4210);
PAINT MONO (-3640 4210);
FORCEPROP 0 LASTPIN (-3650 3100) $PN 260
J 0
(-3640 3110);
DISPLAY 0.680851 (-3640 3110);
PAINT MONO (-3640 3110);
FORCEPROP 0 LASTPIN (-3650 3150) $PN 261
J 0
(-3640 3160);
DISPLAY 0.680851 (-3640 3160);
PAINT MONO (-3640 3160);
FORCEPROP 0 LASTPIN (-3650 4250) $PN 178
J 0
(-3640 4260);
DISPLAY 0.680851 (-3640 4260);
PAINT MONO (-3640 4260);
FORCEPROP 0 LASTPIN (-3650 4300) $PN 179
J 0
(-3640 4310);
DISPLAY 0.680851 (-3640 4310);
PAINT MONO (-3640 4310);
FORCEPROP 0 LASTPIN (-3650 3200) $PN 271
J 0
(-3640 3210);
DISPLAY 0.680851 (-3640 3210);
PAINT MONO (-3640 3210);
FORCEPROP 0 LASTPIN (-3650 3250) $PN 272
J 0
(-3640 3260);
DISPLAY 0.680851 (-3640 3260);
PAINT MONO (-3640 3260);
FORCEPROP 0 LASTPIN (-3650 4350) $PN 189
J 0
(-3640 4360);
DISPLAY 0.680851 (-3640 4360);
PAINT MONO (-3640 4360);
FORCEPROP 0 LASTPIN (-3650 4400) $PN 190
J 0
(-3640 4410);
DISPLAY 0.680851 (-3640 4410);
PAINT MONO (-3640 4410);
FORCEPROP 0 LASTPIN (-3650 3300) $PN 282
J 0
(-3640 3310);
DISPLAY 0.680851 (-3640 3310);
PAINT MONO (-3640 3310);
FORCEPROP 0 LASTPIN (-3650 3350) $PN 283
J 0
(-3640 3360);
DISPLAY 0.680851 (-3640 3360);
PAINT MONO (-3640 3360);
FORCEPROP 0 LASTPIN (-3650 4450) $PN 200
J 0
(-3640 4460);
DISPLAY 0.680851 (-3640 4460);
PAINT MONO (-3640 4460);
FORCEPROP 0 LASTPIN (-3650 4500) $PN 201
J 0
(-3640 4510);
DISPLAY 0.680851 (-3640 4510);
PAINT MONO (-3640 4510);
FORCEPROP 0 LASTPIN (-3650 3400) $PN 94
J 0
(-3640 3410);
DISPLAY 0.680851 (-3640 3410);
PAINT MONO (-3640 3410);
FORCEPROP 0 LASTPIN (-3650 3450) $PN 93
J 0
(-3640 3460);
DISPLAY 0.680851 (-3640 3460);
PAINT MONO (-3640 3460);
FORCEPROP 2 LAST VALUE SCONN288_DDR506112002KQ
J 0
(-4850 4875);
DISPLAY 0.489362 (-4850 4875);
PAINT SKYBLUE (-4850 4875);
FORCEPROP 2 LAST PART_TYPE SMLF
J 0
(-4850 4925);
DISPLAY 1.021277 (-4850 4925);
FORCEPROP 1 LAST PART_NUMBER DFHST8FS479
J 0
(-5000 4750);
DISPLAY 0.468085 (-5000 4750);
PAINT SKYBLUE (-5000 4750);
FORCEPROP 1 LAST MATERIAL IO
J 0
(-5000 4675);
DISPLAY 0.468085 (-5000 4675);
PAINT SKYBLUE (-5000 4675);
FORCEPROP 1 LAST CDS_LMAN_SYM_OUTLINE -600,1150,600,-1150
J 0
(-4400 3500);
DISPLAY 0.468085 (-4400 3500);
PAINT GREEN (-4400 3500);
DISPLAY INVISIBLE (-4400 3500);
FORCEPROP 1 LAST PATH I236
J 0
(-4400 3500);
DISPLAY 0.723404 (-4400 3500);
PAINT GREEN (-4400 3500);
DISPLAY INVISIBLE (-4400 3500);
FORCEPROP 1 LAST NEEDS_NO_SIZE TRUE
J 0
(-4400 3500);
DISPLAY 0.723404 (-4400 3500);
PAINT GREEN (-4400 3500);
DISPLAY INVISIBLE (-4400 3500);
FORCEPROP 2 LAST CDS_LIB pure_quanta
J 0
(-4400 3500);
DISPLAY INVISIBLE (-4400 3500);
FORCEADD GND..1
(-2875 5175);
FORCEPROP 3 LASTPIN (-2875 5225) SIG_NAME GND\g
J 0
(-2865 5235);
DISPLAY 0.659574 (-2865 5235);
PAINT MONO (-2865 5235);
DISPLAY INVISIBLE (-2865 5235);
FORCEPROP 2 LAST CDS_LIB pure_quanta_power
J 0
(-2875 5175);
DISPLAY INVISIBLE (-2875 5175);
FORCEPROP 2 LAST BOM_COST MEM
J 0
(-2850 5300);
DISPLAY 0.659574 (-2850 5300);
DISPLAY INVISIBLE (-2850 5300);
FORCEPROP 1 LAST SIZE 1B
J 0
(-2800 5125);
DISPLAY 0.723404 (-2800 5125);
PAINT GREEN (-2800 5125);
DISPLAY INVISIBLE (-2800 5125);
FORCEPROP 1 LAST PATH I237
J 0
(-2800 5175);
DISPLAY 0.872340 (-2800 5175);
PAINT AQUA (-2800 5175);
DISPLAY INVISIBLE (-2800 5175);
FORCEPROP 2 LAST ROOM MEM_EFGH_DECOUPLING_CAPS
J 0
(-2850 5250);
DISPLAY 0.659574 (-2850 5250);
PAINT RED (-2850 5250);
DISPLAY INVISIBLE (-2850 5250);
FORCEPROP 1 LAST HDL_POWER GND
J 0
(-2875 5325);
DISPLAY 0.723404 (-2875 5325);
PAINT GREEN (-2875 5325);
DISPLAY INVISIBLE (-2875 5325);
FORCEADD Q_CAP..1
R 2
(-2875 5525);
FORCEPROP 1 LAST LOCATION C175
J 2
(-2925 5625);
DISPLAY 0.489362 (-2925 5625);
PAINT SKYBLUE (-2925 5625);
FORCEPROP 0 LAST $SEC 1
J 0
(-2925 5675);
DISPLAY 0.680851 (-2925 5675);
PAINT MONO (-2925 5675);
DISPLAY INVISIBLE (-2925 5675);
FORCEPROP 0 LAST CDS_SEC 1
J 0
(-2925 5675);
DISPLAY 0.680851 (-2925 5675);
DISPLAY INVISIBLE (-2925 5675);
FORCEPROP 1 LASTPIN (-2875 5625) $PN 1
J 2
(-2885 5605);
DISPLAY 0.489362 (-2885 5605);
PAINT MONO (-2885 5605);
FORCEPROP 1 LASTPIN (-2875 5425) $PN 2
J 2
(-2885 5405);
DISPLAY 0.489362 (-2885 5405);
PAINT MONO (-2885 5405);
FORCEPROP 1 LAST VOLTAGE 25V
J 2
(-2925 5525);
DISPLAY 0.489362 (-2925 5525);
PAINT SKYBLUE (-2925 5525);
FORCEPROP 1 LAST VALUE 10UF
J 2
(-2925 5575);
DISPLAY 0.489362 (-2925 5575);
PAINT SKYBLUE (-2925 5575);
FORCEPROP 1 LAST MATERIAL X6S
J 2
(-2925 5425);
DISPLAY 0.489362 (-2925 5425);
PAINT SKYBLUE (-2925 5425);
FORCEPROP 1 LAST PART_NUMBER CH6104KEA00
J 2
(-2925 5375);
DISPLAY 0.489362 (-2925 5375);
PAINT SKYBLUE (-2925 5375);
FORCEPROP 1 LAST TOLERANCE 10%
J 2
(-2925 5475);
DISPLAY 0.489362 (-2925 5475);
PAINT SKYBLUE (-2925 5475);
FORCEPROP 1 LAST PACK_TYPE C0805
J 2
(-2925 5325);
DISPLAY 0.489362 (-2925 5325);
PAINT SKYBLUE (-2925 5325);
FORCEPROP 0 LAST BOM_COST MEM
J 2
(-2930 5670);
DISPLAY 0.595745 (-2930 5670);
PAINT MONO (-2930 5670);
DISPLAY INVISIBLE (-2930 5670);
FORCEPROP 2 LAST CDS_LIB pure_quanta
J 0
(-2875 5525);
DISPLAY INVISIBLE (-2875 5525);
FORCEPROP 1 LAST PATH I238
J 2
(-2925 5675);
DISPLAY 0.978723 (-2925 5675);
PAINT WHITE (-2925 5675);
DISPLAY INVISIBLE (-2925 5675);
FORCEPROP 0 LAST ROOM MEM_CH_A_CPU0_DIMM1
J 2
(-2930 5670);
DISPLAY 0.595745 (-2930 5670);
PAINT RED (-2930 5670);
DISPLAY INVISIBLE (-2930 5670);
FORCEADD Q_CAP..1
R 2
(-2300 5525);
FORCEPROP 1 LAST LOCATION C177
J 2
(-2350 5625);
DISPLAY 0.489362 (-2350 5625);
PAINT SKYBLUE (-2350 5625);
FORCEPROP 0 LAST $SEC 1
J 0
(-2350 5675);
DISPLAY 0.680851 (-2350 5675);
PAINT MONO (-2350 5675);
DISPLAY INVISIBLE (-2350 5675);
FORCEPROP 0 LAST CDS_SEC 1
J 0
(-2350 5675);
DISPLAY 0.680851 (-2350 5675);
DISPLAY INVISIBLE (-2350 5675);
FORCEPROP 1 LASTPIN (-2300 5625) $PN 1
J 2
(-2310 5605);
DISPLAY 0.489362 (-2310 5605);
PAINT MONO (-2310 5605);
FORCEPROP 1 LASTPIN (-2300 5425) $PN 2
J 2
(-2310 5405);
DISPLAY 0.489362 (-2310 5405);
PAINT MONO (-2310 5405);
FORCEPROP 1 LAST MATERIAL X6S
J 2
(-2350 5425);
DISPLAY 0.489362 (-2350 5425);
PAINT SKYBLUE (-2350 5425);
FORCEPROP 1 LAST VALUE 10UF
J 2
(-2350 5575);
DISPLAY 0.489362 (-2350 5575);
PAINT SKYBLUE (-2350 5575);
FORCEPROP 1 LAST PACK_TYPE C0805
J 2
(-2350 5325);
DISPLAY 0.489362 (-2350 5325);
PAINT SKYBLUE (-2350 5325);
FORCEPROP 1 LAST PART_NUMBER CH6104KEA00
J 2
(-2350 5375);
DISPLAY 0.489362 (-2350 5375);
PAINT SKYBLUE (-2350 5375);
FORCEPROP 1 LAST VOLTAGE 25V
J 2
(-2350 5525);
DISPLAY 0.489362 (-2350 5525);
PAINT SKYBLUE (-2350 5525);
FORCEPROP 1 LAST TOLERANCE 10%
J 2
(-2350 5475);
DISPLAY 0.489362 (-2350 5475);
PAINT SKYBLUE (-2350 5475);
FORCEPROP 0 LAST BOM_COST MEM
J 2
(-2355 5670);
DISPLAY 0.595745 (-2355 5670);
PAINT MONO (-2355 5670);
DISPLAY INVISIBLE (-2355 5670);
FORCEPROP 2 LAST CDS_LIB pure_quanta
J 0
(-2300 5525);
DISPLAY INVISIBLE (-2300 5525);
FORCEPROP 1 LAST PATH I239
J 2
(-2350 5675);
DISPLAY 0.978723 (-2350 5675);
PAINT WHITE (-2350 5675);
DISPLAY INVISIBLE (-2350 5675);
FORCEPROP 0 LAST ROOM MEM_CH_A_CPU0_DIMM1
J 2
(-2355 5670);
DISPLAY 0.595745 (-2355 5670);
PAINT RED (-2355 5670);
DISPLAY INVISIBLE (-2355 5670);
FORCEADD TAP..1
R 2
(-7775 3375);
FORCEPROP 3 LASTPIN (-7725 3375) SIG_NAME M_B_CPU1_SB_CB<1>
J 0
(-7715 3385);
DISPLAY 0.659574 (-7715 3385);
PAINT MONO (-7715 3385);
DISPLAY INVISIBLE (-7715 3385);
FORCEPROP 1 LASTPIN (-7725 3375) BN 1
J 2
(-7713 3383);
DISPLAY 0.489362 (-7713 3383);
PAINT GREEN (-7713 3383);
FORCEPROP 2 LAST CDS_LIB mstr_standard
J 0
(-7775 3375);
DISPLAY 0.723404 (-7775 3375);
PAINT MONO (-7775 3375);
DISPLAY INVISIBLE (-7775 3375);
FORCEPROP 1 LAST BODY_TYPE PLUMBING
J 2
(-7775 3425);
DISPLAY 0.872340 (-7775 3425);
PAINT GREEN (-7775 3425);
DISPLAY INVISIBLE (-7775 3425);
FORCEPROP 1 LAST HDL_TAP TRUE
J 2
(-8100 3250);
DISPLAY 0.872340 (-8100 3250);
DISPLAY INVISIBLE (-8100 3250);
FORCEPROP 1 LAST PATH I24
J 2
(-7773 3375);
DISPLAY 0.872340 (-7773 3375);
PAINT GREEN (-7773 3375);
DISPLAY INVISIBLE (-7773 3375);
FORCEADD UNIVERSAL_POWER..1
(-2875 5850);
FORCEPROP 3 LASTPIN (-2875 5800) SIG_NAME P12V_MEM_2\g
J 0
(-2865 5810);
DISPLAY 0.659574 (-2865 5810);
PAINT MONO (-2865 5810);
DISPLAY INVISIBLE (-2865 5810);
FORCEPROP 1 LAST HDL_POWER P12V_MEM_2
J 1
(-2875 5900);
DISPLAY 0.489362 (-2875 5900);
PAINT GREEN (-2875 5900);
FORCEPROP 2 LAST CDS_LIB pure_quanta_power
J 0
(-2875 5850);
DISPLAY INVISIBLE (-2875 5850);
FORCEPROP 1 LAST PATH I240
J 0
(-2825 5875);
DISPLAY 0.872340 (-2825 5875);
PAINT AQUA (-2825 5875);
DISPLAY INVISIBLE (-2825 5875);
FORCEADD OFFPAGE..1
(-8400 2825);
FORCEPROP 2 LAST $XR5 102 
J 0
(-9192 2825);
DISPLAY 0.638298 (-9192 2825);
PAINT MONO (-9192 2825);
FORCEPROP 2 LAST $XR4 101 
J 0
(-9072 2825);
DISPLAY 0.638298 (-9072 2825);
PAINT MONO (-9072 2825);
FORCEPROP 2 LAST $XR3 100 
J 0
(-8952 2825);
DISPLAY 0.638298 (-8952 2825);
PAINT MONO (-8952 2825);
FORCEPROP 2 LAST $XR2 99 
J 0
(-8832 2825);
DISPLAY 0.638298 (-8832 2825);
PAINT MONO (-8832 2825);
FORCEPROP 2 LAST $XR1 97 
J 0
(-8742 2825);
DISPLAY 0.638298 (-8742 2825);
PAINT MONO (-8742 2825);
FORCEPROP 2 LAST $XR0 136 
J 0
(-8652 2825);
DISPLAY 0.638298 (-8652 2825);
PAINT MONO (-8652 2825);
FORCEPROP 2 LAST PATH I241
J 0
(-8675 2875);
DISPLAY 0.680851 (-8675 2875);
DISPLAY INVISIBLE (-8675 2875);
FORCEPROP 1 LAST COMMENT_BODY TRUE
J 0
(-8275 2725);
DISPLAY 0.872340 (-8275 2725);
PAINT GREEN (-8275 2725);
DISPLAY INVISIBLE (-8275 2725);
FORCEPROP 1 LAST OFFPAGE TRUE
J 0
(-8075 2700);
DISPLAY 0.872340 (-8075 2700);
PAINT GREEN (-8075 2700);
DISPLAY INVISIBLE (-8075 2700);
FORCEPROP 2 LAST CDS_LIB mstr_standard
J 0
(-8400 2825);
DISPLAY 0.808511 (-8400 2825);
DISPLAY INVISIBLE (-8400 2825);
FORCEADD Q_RES..1
(-7825 2825);
FORCEPROP 1 LAST $LOCATION R1581
J 0
(-7875 2850);
DISPLAY 0.510638 (-7875 2850);
PAINT SKYBLUE (-7875 2850);
FORCEPROP 0 LAST CDS_LOCATION R1581
J 0
(-7875 2925);
DISPLAY 0.680851 (-7875 2925);
DISPLAY INVISIBLE (-7875 2925);
FORCEPROP 0 LAST $SEC 1
J 0
(-7875 2925);
DISPLAY 0.680851 (-7875 2925);
PAINT MONO (-7875 2925);
DISPLAY INVISIBLE (-7875 2925);
FORCEPROP 0 LAST CDS_SEC 1
J 0
(-7875 2925);
DISPLAY 0.680851 (-7875 2925);
DISPLAY INVISIBLE (-7875 2925);
FORCEPROP 1 LASTPIN (-7925 2825) $PN 1
J 0
(-7913 2837);
DISPLAY 0.787234 (-7913 2837);
PAINT MONO (-7913 2837);
FORCEPROP 1 LASTPIN (-7725 2825) $PN 2
J 0
(-7763 2837);
DISPLAY 0.787234 (-7763 2837);
PAINT MONO (-7763 2837);
FORCEPROP 1 LAST VALUE 49.9
J 2
(-7675 2875);
DISPLAY 0.510638 (-7675 2875);
PAINT SKYBLUE (-7675 2875);
FORCEPROP 2 LAST CDS_LIB pure_quanta
J 0
(-7825 2825);
DISPLAY INVISIBLE (-7825 2825);
FORCEPROP 1 LAST PATH I242
J 0
(-7875 2975);
DISPLAY 0.978723 (-7875 2975);
PAINT WHITE (-7875 2975);
DISPLAY INVISIBLE (-7875 2975);
FORCEPROP 1 LAST MATERIAL CHIP
J 0
(-7825 2675);
DISPLAY 0.978723 (-7825 2675);
DISPLAY INVISIBLE (-7825 2675);
FORCEPROP 1 LAST PACK_TYPE 0402LF
J 0
(-7575 2675);
DISPLAY 0.978723 (-7575 2675);
DISPLAY INVISIBLE (-7575 2675);
FORCEPROP 1 LAST WATTAGE 1/16W
J 2
(-7850 2675);
DISPLAY 0.978723 (-7850 2675);
DISPLAY INVISIBLE (-7850 2675);
FORCEPROP 1 LAST TOLERANCE 1%
J 0
(-7825 2725);
DISPLAY 0.978723 (-7825 2725);
DISPLAY INVISIBLE (-7825 2725);
FORCEPROP 1 LAST PART_NUMBER CS04992FB07
J 0
(-7875 2925);
DISPLAY 0.978723 (-7875 2925);
DISPLAY INVISIBLE (-7875 2925);
FORCEADD TAP..1
R 2
(-7775 3425);
FORCEPROP 3 LASTPIN (-7725 3425) SIG_NAME M_B_CPU1_SB_CB<2>
J 0
(-7715 3435);
DISPLAY 0.659574 (-7715 3435);
PAINT MONO (-7715 3435);
DISPLAY INVISIBLE (-7715 3435);
FORCEPROP 1 LASTPIN (-7725 3425) BN 2
J 2
(-7713 3433);
DISPLAY 0.489362 (-7713 3433);
PAINT GREEN (-7713 3433);
FORCEPROP 2 LAST CDS_LIB mstr_standard
J 0
(-7775 3425);
DISPLAY 0.723404 (-7775 3425);
PAINT MONO (-7775 3425);
DISPLAY INVISIBLE (-7775 3425);
FORCEPROP 1 LAST BODY_TYPE PLUMBING
J 2
(-7775 3475);
DISPLAY 0.872340 (-7775 3475);
PAINT GREEN (-7775 3475);
DISPLAY INVISIBLE (-7775 3475);
FORCEPROP 1 LAST HDL_TAP TRUE
J 2
(-8100 3300);
DISPLAY 0.872340 (-8100 3300);
DISPLAY INVISIBLE (-8100 3300);
FORCEPROP 1 LAST PATH I25
J 2
(-7773 3425);
DISPLAY 0.872340 (-7773 3425);
PAINT GREEN (-7773 3425);
DISPLAY INVISIBLE (-7773 3425);
FORCEADD TAP..1
R 2
(-7775 3525);
FORCEPROP 3 LASTPIN (-7725 3525) SIG_NAME M_B_CPU1_SB_CB<4>
J 0
(-7715 3535);
DISPLAY 0.659574 (-7715 3535);
PAINT MONO (-7715 3535);
DISPLAY INVISIBLE (-7715 3535);
FORCEPROP 1 LASTPIN (-7725 3525) BN 4
J 2
(-7713 3533);
DISPLAY 0.489362 (-7713 3533);
PAINT GREEN (-7713 3533);
FORCEPROP 2 LAST CDS_LIB mstr_standard
J 0
(-7775 3525);
DISPLAY 0.723404 (-7775 3525);
PAINT MONO (-7775 3525);
DISPLAY INVISIBLE (-7775 3525);
FORCEPROP 1 LAST BODY_TYPE PLUMBING
J 2
(-7775 3575);
DISPLAY 0.872340 (-7775 3575);
PAINT GREEN (-7775 3575);
DISPLAY INVISIBLE (-7775 3575);
FORCEPROP 1 LAST HDL_TAP TRUE
J 2
(-8100 3400);
DISPLAY 0.872340 (-8100 3400);
DISPLAY INVISIBLE (-8100 3400);
FORCEPROP 1 LAST PATH I26
J 2
(-7773 3525);
DISPLAY 0.872340 (-7773 3525);
PAINT GREEN (-7773 3525);
DISPLAY INVISIBLE (-7773 3525);
FORCEADD TAP..1
R 2
(-7775 3475);
FORCEPROP 3 LASTPIN (-7725 3475) SIG_NAME M_B_CPU1_SB_CB<3>
J 0
(-7715 3485);
DISPLAY 0.659574 (-7715 3485);
PAINT MONO (-7715 3485);
DISPLAY INVISIBLE (-7715 3485);
FORCEPROP 1 LASTPIN (-7725 3475) BN 3
J 2
(-7713 3483);
DISPLAY 0.489362 (-7713 3483);
PAINT GREEN (-7713 3483);
FORCEPROP 2 LAST CDS_LIB mstr_standard
J 0
(-7775 3475);
DISPLAY 0.723404 (-7775 3475);
PAINT MONO (-7775 3475);
DISPLAY INVISIBLE (-7775 3475);
FORCEPROP 1 LAST BODY_TYPE PLUMBING
J 2
(-7775 3525);
DISPLAY 0.872340 (-7775 3525);
PAINT GREEN (-7775 3525);
DISPLAY INVISIBLE (-7775 3525);
FORCEPROP 1 LAST HDL_TAP TRUE
J 2
(-8100 3350);
DISPLAY 0.872340 (-8100 3350);
DISPLAY INVISIBLE (-8100 3350);
FORCEPROP 1 LAST PATH I27
J 2
(-7773 3475);
DISPLAY 0.872340 (-7773 3475);
PAINT GREEN (-7773 3475);
DISPLAY INVISIBLE (-7773 3475);
FORCEADD TAP..1
R 2
(-7775 3575);
FORCEPROP 3 LASTPIN (-7725 3575) SIG_NAME M_B_CPU1_SB_CB<5>
J 0
(-7715 3585);
DISPLAY 0.659574 (-7715 3585);
PAINT MONO (-7715 3585);
DISPLAY INVISIBLE (-7715 3585);
FORCEPROP 1 LASTPIN (-7725 3575) BN 5
J 2
(-7713 3583);
DISPLAY 0.489362 (-7713 3583);
PAINT GREEN (-7713 3583);
FORCEPROP 2 LAST CDS_LIB mstr_standard
J 0
(-7775 3575);
DISPLAY 0.723404 (-7775 3575);
PAINT MONO (-7775 3575);
DISPLAY INVISIBLE (-7775 3575);
FORCEPROP 1 LAST BODY_TYPE PLUMBING
J 2
(-7775 3625);
DISPLAY 0.872340 (-7775 3625);
PAINT GREEN (-7775 3625);
DISPLAY INVISIBLE (-7775 3625);
FORCEPROP 1 LAST HDL_TAP TRUE
J 2
(-8100 3450);
DISPLAY 0.872340 (-8100 3450);
DISPLAY INVISIBLE (-8100 3450);
FORCEPROP 1 LAST PATH I28
J 2
(-7773 3575);
DISPLAY 0.872340 (-7773 3575);
PAINT GREEN (-7773 3575);
DISPLAY INVISIBLE (-7773 3575);
FORCEADD TAP..1
R 2
(-7775 3675);
FORCEPROP 3 LASTPIN (-7725 3675) SIG_NAME M_B_CPU1_SB_CB<7>
J 0
(-7715 3685);
DISPLAY 0.659574 (-7715 3685);
PAINT MONO (-7715 3685);
DISPLAY INVISIBLE (-7715 3685);
FORCEPROP 1 LASTPIN (-7725 3675) BN 7
J 2
(-7713 3683);
DISPLAY 0.489362 (-7713 3683);
PAINT GREEN (-7713 3683);
FORCEPROP 2 LAST CDS_LIB mstr_standard
J 0
(-7775 3675);
DISPLAY 0.723404 (-7775 3675);
PAINT MONO (-7775 3675);
DISPLAY INVISIBLE (-7775 3675);
FORCEPROP 1 LAST BODY_TYPE PLUMBING
J 2
(-7775 3725);
DISPLAY 0.872340 (-7775 3725);
PAINT GREEN (-7775 3725);
DISPLAY INVISIBLE (-7775 3725);
FORCEPROP 1 LAST HDL_TAP TRUE
J 2
(-8100 3550);
DISPLAY 0.872340 (-8100 3550);
DISPLAY INVISIBLE (-8100 3550);
FORCEPROP 1 LAST PATH I29
J 2
(-7773 3675);
DISPLAY 0.872340 (-7773 3675);
PAINT GREEN (-7773 3675);
DISPLAY INVISIBLE (-7773 3675);
FORCEADD TAP..1
R 2
(-7775 3625);
FORCEPROP 3 LASTPIN (-7725 3625) SIG_NAME M_B_CPU1_SB_CB<6>
J 0
(-7715 3635);
DISPLAY 0.659574 (-7715 3635);
PAINT MONO (-7715 3635);
DISPLAY INVISIBLE (-7715 3635);
FORCEPROP 1 LASTPIN (-7725 3625) BN 6
J 2
(-7713 3633);
DISPLAY 0.489362 (-7713 3633);
PAINT GREEN (-7713 3633);
FORCEPROP 2 LAST CDS_LIB mstr_standard
J 0
(-7775 3625);
DISPLAY 0.723404 (-7775 3625);
PAINT MONO (-7775 3625);
DISPLAY INVISIBLE (-7775 3625);
FORCEPROP 1 LAST BODY_TYPE PLUMBING
J 2
(-7775 3675);
DISPLAY 0.872340 (-7775 3675);
PAINT GREEN (-7775 3675);
DISPLAY INVISIBLE (-7775 3675);
FORCEPROP 1 LAST HDL_TAP TRUE
J 2
(-8100 3500);
DISPLAY 0.872340 (-8100 3500);
DISPLAY INVISIBLE (-8100 3500);
FORCEPROP 1 LAST PATH I30
J 2
(-7773 3625);
DISPLAY 0.872340 (-7773 3625);
PAINT GREEN (-7773 3625);
DISPLAY INVISIBLE (-7773 3625);
FORCEADD TAP..1
R 2
(-7775 3775);
FORCEPROP 3 LASTPIN (-7725 3775) SIG_NAME M_B_CPU1_SA_CB<0>
J 0
(-7715 3785);
DISPLAY 0.659574 (-7715 3785);
PAINT MONO (-7715 3785);
DISPLAY INVISIBLE (-7715 3785);
FORCEPROP 1 LASTPIN (-7725 3775) BN 0
J 2
(-7713 3783);
DISPLAY 0.489362 (-7713 3783);
PAINT GREEN (-7713 3783);
FORCEPROP 2 LAST CDS_LIB mstr_standard
J 0
(-7775 3775);
DISPLAY 0.723404 (-7775 3775);
PAINT MONO (-7775 3775);
DISPLAY INVISIBLE (-7775 3775);
FORCEPROP 1 LAST BODY_TYPE PLUMBING
J 2
(-7775 3825);
DISPLAY 0.872340 (-7775 3825);
PAINT GREEN (-7775 3825);
DISPLAY INVISIBLE (-7775 3825);
FORCEPROP 1 LAST HDL_TAP TRUE
J 2
(-8100 3650);
DISPLAY 0.872340 (-8100 3650);
DISPLAY INVISIBLE (-8100 3650);
FORCEPROP 1 LAST PATH I31
J 2
(-7773 3775);
DISPLAY 0.872340 (-7773 3775);
PAINT GREEN (-7773 3775);
DISPLAY INVISIBLE (-7773 3775);
FORCEADD TAP..1
R 2
(-7775 3825);
FORCEPROP 3 LASTPIN (-7725 3825) SIG_NAME M_B_CPU1_SA_CB<1>
J 0
(-7715 3835);
DISPLAY 0.659574 (-7715 3835);
PAINT MONO (-7715 3835);
DISPLAY INVISIBLE (-7715 3835);
FORCEPROP 1 LASTPIN (-7725 3825) BN 1
J 2
(-7713 3833);
DISPLAY 0.489362 (-7713 3833);
PAINT GREEN (-7713 3833);
FORCEPROP 2 LAST CDS_LIB mstr_standard
J 0
(-7775 3825);
DISPLAY 0.723404 (-7775 3825);
PAINT MONO (-7775 3825);
DISPLAY INVISIBLE (-7775 3825);
FORCEPROP 1 LAST BODY_TYPE PLUMBING
J 2
(-7775 3875);
DISPLAY 0.872340 (-7775 3875);
PAINT GREEN (-7775 3875);
DISPLAY INVISIBLE (-7775 3875);
FORCEPROP 1 LAST HDL_TAP TRUE
J 2
(-8100 3700);
DISPLAY 0.872340 (-8100 3700);
DISPLAY INVISIBLE (-8100 3700);
FORCEPROP 1 LAST PATH I32
J 2
(-7773 3825);
DISPLAY 0.872340 (-7773 3825);
PAINT GREEN (-7773 3825);
DISPLAY INVISIBLE (-7773 3825);
FORCEADD TAP..1
R 2
(-7775 3875);
FORCEPROP 3 LASTPIN (-7725 3875) SIG_NAME M_B_CPU1_SA_CB<2>
J 0
(-7715 3885);
DISPLAY 0.659574 (-7715 3885);
PAINT MONO (-7715 3885);
DISPLAY INVISIBLE (-7715 3885);
FORCEPROP 1 LASTPIN (-7725 3875) BN 2
J 2
(-7713 3883);
DISPLAY 0.489362 (-7713 3883);
PAINT GREEN (-7713 3883);
FORCEPROP 2 LAST CDS_LIB mstr_standard
J 0
(-7775 3875);
DISPLAY 0.723404 (-7775 3875);
PAINT MONO (-7775 3875);
DISPLAY INVISIBLE (-7775 3875);
FORCEPROP 1 LAST BODY_TYPE PLUMBING
J 2
(-7775 3925);
DISPLAY 0.872340 (-7775 3925);
PAINT GREEN (-7775 3925);
DISPLAY INVISIBLE (-7775 3925);
FORCEPROP 1 LAST HDL_TAP TRUE
J 2
(-8100 3750);
DISPLAY 0.872340 (-8100 3750);
DISPLAY INVISIBLE (-8100 3750);
FORCEPROP 1 LAST PATH I33
J 2
(-7773 3875);
DISPLAY 0.872340 (-7773 3875);
PAINT GREEN (-7773 3875);
DISPLAY INVISIBLE (-7773 3875);
FORCEADD TAP..1
R 2
(-7775 3925);
FORCEPROP 3 LASTPIN (-7725 3925) SIG_NAME M_B_CPU1_SA_CB<3>
J 0
(-7715 3935);
DISPLAY 0.659574 (-7715 3935);
PAINT MONO (-7715 3935);
DISPLAY INVISIBLE (-7715 3935);
FORCEPROP 1 LASTPIN (-7725 3925) BN 3
J 2
(-7713 3933);
DISPLAY 0.489362 (-7713 3933);
PAINT GREEN (-7713 3933);
FORCEPROP 2 LAST CDS_LIB mstr_standard
J 0
(-7775 3925);
DISPLAY 0.723404 (-7775 3925);
PAINT MONO (-7775 3925);
DISPLAY INVISIBLE (-7775 3925);
FORCEPROP 1 LAST BODY_TYPE PLUMBING
J 2
(-7775 3975);
DISPLAY 0.872340 (-7775 3975);
PAINT GREEN (-7775 3975);
DISPLAY INVISIBLE (-7775 3975);
FORCEPROP 1 LAST HDL_TAP TRUE
J 2
(-8100 3800);
DISPLAY 0.872340 (-8100 3800);
DISPLAY INVISIBLE (-8100 3800);
FORCEPROP 1 LAST PATH I34
J 2
(-7773 3925);
DISPLAY 0.872340 (-7773 3925);
PAINT GREEN (-7773 3925);
DISPLAY INVISIBLE (-7773 3925);
FORCEADD TAP..1
R 2
(-7775 4025);
FORCEPROP 3 LASTPIN (-7725 4025) SIG_NAME M_B_CPU1_SA_CB<5>
J 0
(-7715 4035);
DISPLAY 0.659574 (-7715 4035);
PAINT MONO (-7715 4035);
DISPLAY INVISIBLE (-7715 4035);
FORCEPROP 1 LASTPIN (-7725 4025) BN 5
J 2
(-7713 4033);
DISPLAY 0.489362 (-7713 4033);
PAINT GREEN (-7713 4033);
FORCEPROP 2 LAST CDS_LIB mstr_standard
J 0
(-7775 4025);
DISPLAY 0.723404 (-7775 4025);
PAINT MONO (-7775 4025);
DISPLAY INVISIBLE (-7775 4025);
FORCEPROP 1 LAST BODY_TYPE PLUMBING
J 2
(-7775 4075);
DISPLAY 0.872340 (-7775 4075);
PAINT GREEN (-7775 4075);
DISPLAY INVISIBLE (-7775 4075);
FORCEPROP 1 LAST HDL_TAP TRUE
J 2
(-8100 3900);
DISPLAY 0.872340 (-8100 3900);
DISPLAY INVISIBLE (-8100 3900);
FORCEPROP 1 LAST PATH I35
J 2
(-7773 4025);
DISPLAY 0.872340 (-7773 4025);
PAINT GREEN (-7773 4025);
DISPLAY INVISIBLE (-7773 4025);
FORCEADD TAP..1
R 2
(-7775 3975);
FORCEPROP 3 LASTPIN (-7725 3975) SIG_NAME M_B_CPU1_SA_CB<4>
J 0
(-7715 3985);
DISPLAY 0.659574 (-7715 3985);
PAINT MONO (-7715 3985);
DISPLAY INVISIBLE (-7715 3985);
FORCEPROP 1 LASTPIN (-7725 3975) BN 4
J 2
(-7713 3983);
DISPLAY 0.489362 (-7713 3983);
PAINT GREEN (-7713 3983);
FORCEPROP 2 LAST CDS_LIB mstr_standard
J 0
(-7775 3975);
DISPLAY 0.723404 (-7775 3975);
PAINT MONO (-7775 3975);
DISPLAY INVISIBLE (-7775 3975);
FORCEPROP 1 LAST BODY_TYPE PLUMBING
J 2
(-7775 4025);
DISPLAY 0.872340 (-7775 4025);
PAINT GREEN (-7775 4025);
DISPLAY INVISIBLE (-7775 4025);
FORCEPROP 1 LAST HDL_TAP TRUE
J 2
(-8100 3850);
DISPLAY 0.872340 (-8100 3850);
DISPLAY INVISIBLE (-8100 3850);
FORCEPROP 1 LAST PATH I36
J 2
(-7773 3975);
DISPLAY 0.872340 (-7773 3975);
PAINT GREEN (-7773 3975);
DISPLAY INVISIBLE (-7773 3975);
FORCEADD TAP..1
R 2
(-7775 4075);
FORCEPROP 3 LASTPIN (-7725 4075) SIG_NAME M_B_CPU1_SA_CB<6>
J 0
(-7715 4085);
DISPLAY 0.659574 (-7715 4085);
PAINT MONO (-7715 4085);
DISPLAY INVISIBLE (-7715 4085);
FORCEPROP 1 LASTPIN (-7725 4075) BN 6
J 2
(-7713 4083);
DISPLAY 0.489362 (-7713 4083);
PAINT GREEN (-7713 4083);
FORCEPROP 2 LAST CDS_LIB mstr_standard
J 0
(-7775 4075);
DISPLAY 0.723404 (-7775 4075);
PAINT MONO (-7775 4075);
DISPLAY INVISIBLE (-7775 4075);
FORCEPROP 1 LAST BODY_TYPE PLUMBING
J 2
(-7775 4125);
DISPLAY 0.872340 (-7775 4125);
PAINT GREEN (-7775 4125);
DISPLAY INVISIBLE (-7775 4125);
FORCEPROP 1 LAST HDL_TAP TRUE
J 2
(-8100 3950);
DISPLAY 0.872340 (-8100 3950);
DISPLAY INVISIBLE (-8100 3950);
FORCEPROP 1 LAST PATH I37
J 2
(-7773 4075);
DISPLAY 0.872340 (-7773 4075);
PAINT GREEN (-7773 4075);
DISPLAY INVISIBLE (-7773 4075);
FORCEADD TAP..1
(-6075 2375);
FORCEPROP 3 LASTPIN (-6125 2375) SIG_NAME M_B_CPU1_SB_DQ<1>
J 0
(-6115 2385);
DISPLAY 0.659574 (-6115 2385);
PAINT MONO (-6115 2385);
DISPLAY INVISIBLE (-6115 2385);
FORCEPROP 1 LASTPIN (-6125 2375) BN 1
J 0
(-6137 2383);
DISPLAY 0.489362 (-6137 2383);
PAINT GREEN (-6137 2383);
FORCEPROP 2 LAST CDS_LIB mstr_standard
J 0
(-6075 2375);
DISPLAY 0.723404 (-6075 2375);
PAINT MONO (-6075 2375);
DISPLAY INVISIBLE (-6075 2375);
FORCEPROP 1 LAST BODY_TYPE PLUMBING
J 0
(-6075 2425);
DISPLAY 0.872340 (-6075 2425);
PAINT GREEN (-6075 2425);
DISPLAY INVISIBLE (-6075 2425);
FORCEPROP 1 LAST HDL_TAP TRUE
J 0
(-5750 2250);
DISPLAY 0.872340 (-5750 2250);
DISPLAY INVISIBLE (-5750 2250);
FORCEPROP 1 LAST PATH I38
J 0
(-6077 2375);
DISPLAY 0.872340 (-6077 2375);
PAINT GREEN (-6077 2375);
DISPLAY INVISIBLE (-6077 2375);
FORCEADD TAP..1
(-6075 2325);
FORCEPROP 3 LASTPIN (-6125 2325) SIG_NAME M_B_CPU1_SB_DQ<0>
J 0
(-6115 2335);
DISPLAY 0.659574 (-6115 2335);
PAINT MONO (-6115 2335);
DISPLAY INVISIBLE (-6115 2335);
FORCEPROP 1 LASTPIN (-6125 2325) BN 0
J 0
(-6137 2333);
DISPLAY 0.489362 (-6137 2333);
PAINT GREEN (-6137 2333);
FORCEPROP 2 LAST CDS_LIB mstr_standard
J 0
(-6075 2325);
DISPLAY 0.723404 (-6075 2325);
PAINT MONO (-6075 2325);
DISPLAY INVISIBLE (-6075 2325);
FORCEPROP 1 LAST BODY_TYPE PLUMBING
J 0
(-6075 2375);
DISPLAY 0.872340 (-6075 2375);
PAINT GREEN (-6075 2375);
DISPLAY INVISIBLE (-6075 2375);
FORCEPROP 1 LAST HDL_TAP TRUE
J 0
(-5750 2200);
DISPLAY 0.872340 (-5750 2200);
DISPLAY INVISIBLE (-5750 2200);
FORCEPROP 1 LAST PATH I39
J 0
(-6077 2325);
DISPLAY 0.872340 (-6077 2325);
PAINT GREEN (-6077 2325);
DISPLAY INVISIBLE (-6077 2325);
FORCEADD TAP..1
(-6075 2425);
FORCEPROP 3 LASTPIN (-6125 2425) SIG_NAME M_B_CPU1_SB_DQ<2>
J 0
(-6115 2435);
DISPLAY 0.659574 (-6115 2435);
PAINT MONO (-6115 2435);
DISPLAY INVISIBLE (-6115 2435);
FORCEPROP 1 LASTPIN (-6125 2425) BN 2
J 0
(-6137 2433);
DISPLAY 0.489362 (-6137 2433);
PAINT GREEN (-6137 2433);
FORCEPROP 2 LAST CDS_LIB mstr_standard
J 0
(-6075 2425);
DISPLAY 0.723404 (-6075 2425);
PAINT MONO (-6075 2425);
DISPLAY INVISIBLE (-6075 2425);
FORCEPROP 1 LAST BODY_TYPE PLUMBING
J 0
(-6075 2475);
DISPLAY 0.872340 (-6075 2475);
PAINT GREEN (-6075 2475);
DISPLAY INVISIBLE (-6075 2475);
FORCEPROP 1 LAST HDL_TAP TRUE
J 0
(-5750 2300);
DISPLAY 0.872340 (-5750 2300);
DISPLAY INVISIBLE (-5750 2300);
FORCEPROP 1 LAST PATH I40
J 0
(-6077 2425);
DISPLAY 0.872340 (-6077 2425);
PAINT GREEN (-6077 2425);
DISPLAY INVISIBLE (-6077 2425);
FORCEADD TAP..1
(-6075 2475);
FORCEPROP 3 LASTPIN (-6125 2475) SIG_NAME M_B_CPU1_SB_DQ<3>
J 0
(-6115 2485);
DISPLAY 0.659574 (-6115 2485);
PAINT MONO (-6115 2485);
DISPLAY INVISIBLE (-6115 2485);
FORCEPROP 1 LASTPIN (-6125 2475) BN 3
J 0
(-6137 2483);
DISPLAY 0.489362 (-6137 2483);
PAINT GREEN (-6137 2483);
FORCEPROP 2 LAST CDS_LIB mstr_standard
J 0
(-6075 2475);
DISPLAY 0.723404 (-6075 2475);
PAINT MONO (-6075 2475);
DISPLAY INVISIBLE (-6075 2475);
FORCEPROP 1 LAST BODY_TYPE PLUMBING
J 0
(-6075 2525);
DISPLAY 0.872340 (-6075 2525);
PAINT GREEN (-6075 2525);
DISPLAY INVISIBLE (-6075 2525);
FORCEPROP 1 LAST HDL_TAP TRUE
J 0
(-5750 2350);
DISPLAY 0.872340 (-5750 2350);
DISPLAY INVISIBLE (-5750 2350);
FORCEPROP 1 LAST PATH I41
J 0
(-6077 2475);
DISPLAY 0.872340 (-6077 2475);
PAINT GREEN (-6077 2475);
DISPLAY INVISIBLE (-6077 2475);
FORCEADD TAP..1
(-6075 2525);
FORCEPROP 3 LASTPIN (-6125 2525) SIG_NAME M_B_CPU1_SB_DQ<4>
J 0
(-6115 2535);
DISPLAY 0.659574 (-6115 2535);
PAINT MONO (-6115 2535);
DISPLAY INVISIBLE (-6115 2535);
FORCEPROP 1 LASTPIN (-6125 2525) BN 4
J 0
(-6137 2533);
DISPLAY 0.489362 (-6137 2533);
PAINT GREEN (-6137 2533);
FORCEPROP 2 LAST CDS_LIB mstr_standard
J 0
(-6075 2525);
DISPLAY 0.723404 (-6075 2525);
PAINT MONO (-6075 2525);
DISPLAY INVISIBLE (-6075 2525);
FORCEPROP 1 LAST BODY_TYPE PLUMBING
J 0
(-6075 2575);
DISPLAY 0.872340 (-6075 2575);
PAINT GREEN (-6075 2575);
DISPLAY INVISIBLE (-6075 2575);
FORCEPROP 1 LAST HDL_TAP TRUE
J 0
(-5750 2400);
DISPLAY 0.872340 (-5750 2400);
DISPLAY INVISIBLE (-5750 2400);
FORCEPROP 1 LAST PATH I42
J 0
(-6077 2525);
DISPLAY 0.872340 (-6077 2525);
PAINT GREEN (-6077 2525);
DISPLAY INVISIBLE (-6077 2525);
FORCEADD TAP..1
(-6075 2575);
FORCEPROP 3 LASTPIN (-6125 2575) SIG_NAME M_B_CPU1_SB_DQ<5>
J 0
(-6115 2585);
DISPLAY 0.659574 (-6115 2585);
PAINT MONO (-6115 2585);
DISPLAY INVISIBLE (-6115 2585);
FORCEPROP 1 LASTPIN (-6125 2575) BN 5
J 0
(-6137 2583);
DISPLAY 0.489362 (-6137 2583);
PAINT GREEN (-6137 2583);
FORCEPROP 2 LAST CDS_LIB mstr_standard
J 0
(-6075 2575);
DISPLAY 0.723404 (-6075 2575);
PAINT MONO (-6075 2575);
DISPLAY INVISIBLE (-6075 2575);
FORCEPROP 1 LAST BODY_TYPE PLUMBING
J 0
(-6075 2625);
DISPLAY 0.872340 (-6075 2625);
PAINT GREEN (-6075 2625);
DISPLAY INVISIBLE (-6075 2625);
FORCEPROP 1 LAST HDL_TAP TRUE
J 0
(-5750 2450);
DISPLAY 0.872340 (-5750 2450);
DISPLAY INVISIBLE (-5750 2450);
FORCEPROP 1 LAST PATH I43
J 0
(-6077 2575);
DISPLAY 0.872340 (-6077 2575);
PAINT GREEN (-6077 2575);
DISPLAY INVISIBLE (-6077 2575);
FORCEADD TAP..1
(-6075 2675);
FORCEPROP 3 LASTPIN (-6125 2675) SIG_NAME M_B_CPU1_SB_DQ<7>
J 0
(-6115 2685);
DISPLAY 0.659574 (-6115 2685);
PAINT MONO (-6115 2685);
DISPLAY INVISIBLE (-6115 2685);
FORCEPROP 1 LASTPIN (-6125 2675) BN 7
J 0
(-6137 2683);
DISPLAY 0.489362 (-6137 2683);
PAINT GREEN (-6137 2683);
FORCEPROP 2 LAST CDS_LIB mstr_standard
J 0
(-6075 2675);
DISPLAY 0.723404 (-6075 2675);
PAINT MONO (-6075 2675);
DISPLAY INVISIBLE (-6075 2675);
FORCEPROP 1 LAST BODY_TYPE PLUMBING
J 0
(-6075 2725);
DISPLAY 0.872340 (-6075 2725);
PAINT GREEN (-6075 2725);
DISPLAY INVISIBLE (-6075 2725);
FORCEPROP 1 LAST HDL_TAP TRUE
J 0
(-5750 2550);
DISPLAY 0.872340 (-5750 2550);
DISPLAY INVISIBLE (-5750 2550);
FORCEPROP 1 LAST PATH I44
J 0
(-6077 2675);
DISPLAY 0.872340 (-6077 2675);
PAINT GREEN (-6077 2675);
DISPLAY INVISIBLE (-6077 2675);
FORCEADD TAP..1
(-6075 2625);
FORCEPROP 3 LASTPIN (-6125 2625) SIG_NAME M_B_CPU1_SB_DQ<6>
J 0
(-6115 2635);
DISPLAY 0.659574 (-6115 2635);
PAINT MONO (-6115 2635);
DISPLAY INVISIBLE (-6115 2635);
FORCEPROP 1 LASTPIN (-6125 2625) BN 6
J 0
(-6137 2633);
DISPLAY 0.489362 (-6137 2633);
PAINT GREEN (-6137 2633);
FORCEPROP 2 LAST CDS_LIB mstr_standard
J 0
(-6075 2625);
DISPLAY 0.723404 (-6075 2625);
PAINT MONO (-6075 2625);
DISPLAY INVISIBLE (-6075 2625);
FORCEPROP 1 LAST BODY_TYPE PLUMBING
J 0
(-6075 2675);
DISPLAY 0.872340 (-6075 2675);
PAINT GREEN (-6075 2675);
DISPLAY INVISIBLE (-6075 2675);
FORCEPROP 1 LAST HDL_TAP TRUE
J 0
(-5750 2500);
DISPLAY 0.872340 (-5750 2500);
DISPLAY INVISIBLE (-5750 2500);
FORCEPROP 1 LAST PATH I45
J 0
(-6077 2625);
DISPLAY 0.872340 (-6077 2625);
PAINT GREEN (-6077 2625);
DISPLAY INVISIBLE (-6077 2625);
FORCEADD TAP..1
(-6075 2775);
FORCEPROP 3 LASTPIN (-6125 2775) SIG_NAME M_B_CPU1_SB_DQ<9>
J 0
(-6115 2785);
DISPLAY 0.659574 (-6115 2785);
PAINT MONO (-6115 2785);
DISPLAY INVISIBLE (-6115 2785);
FORCEPROP 1 LASTPIN (-6125 2775) BN 9
J 0
(-6137 2783);
DISPLAY 0.489362 (-6137 2783);
PAINT GREEN (-6137 2783);
FORCEPROP 2 LAST CDS_LIB mstr_standard
J 0
(-6075 2775);
DISPLAY 0.723404 (-6075 2775);
PAINT MONO (-6075 2775);
DISPLAY INVISIBLE (-6075 2775);
FORCEPROP 1 LAST BODY_TYPE PLUMBING
J 0
(-6075 2825);
DISPLAY 0.872340 (-6075 2825);
PAINT GREEN (-6075 2825);
DISPLAY INVISIBLE (-6075 2825);
FORCEPROP 1 LAST HDL_TAP TRUE
J 0
(-5750 2650);
DISPLAY 0.872340 (-5750 2650);
DISPLAY INVISIBLE (-5750 2650);
FORCEPROP 1 LAST PATH I46
J 0
(-6077 2775);
DISPLAY 0.872340 (-6077 2775);
PAINT GREEN (-6077 2775);
DISPLAY INVISIBLE (-6077 2775);
FORCEADD TAP..1
(-6075 2725);
FORCEPROP 3 LASTPIN (-6125 2725) SIG_NAME M_B_CPU1_SB_DQ<8>
J 0
(-6115 2735);
DISPLAY 0.659574 (-6115 2735);
PAINT MONO (-6115 2735);
DISPLAY INVISIBLE (-6115 2735);
FORCEPROP 1 LASTPIN (-6125 2725) BN 8
J 0
(-6137 2733);
DISPLAY 0.489362 (-6137 2733);
PAINT GREEN (-6137 2733);
FORCEPROP 2 LAST CDS_LIB mstr_standard
J 0
(-6075 2725);
DISPLAY 0.723404 (-6075 2725);
PAINT MONO (-6075 2725);
DISPLAY INVISIBLE (-6075 2725);
FORCEPROP 1 LAST BODY_TYPE PLUMBING
J 0
(-6075 2775);
DISPLAY 0.872340 (-6075 2775);
PAINT GREEN (-6075 2775);
DISPLAY INVISIBLE (-6075 2775);
FORCEPROP 1 LAST HDL_TAP TRUE
J 0
(-5750 2600);
DISPLAY 0.872340 (-5750 2600);
DISPLAY INVISIBLE (-5750 2600);
FORCEPROP 1 LAST PATH I47
J 0
(-6077 2725);
DISPLAY 0.872340 (-6077 2725);
PAINT GREEN (-6077 2725);
DISPLAY INVISIBLE (-6077 2725);
FORCEADD TAP..1
(-6075 2975);
FORCEPROP 3 LASTPIN (-6125 2975) SIG_NAME M_B_CPU1_SB_DQ<13>
J 0
(-6115 2985);
DISPLAY 0.659574 (-6115 2985);
PAINT MONO (-6115 2985);
DISPLAY INVISIBLE (-6115 2985);
FORCEPROP 1 LASTPIN (-6125 2975) BN 13
J 0
(-6137 2983);
DISPLAY 0.489362 (-6137 2983);
PAINT GREEN (-6137 2983);
FORCEPROP 2 LAST CDS_LIB mstr_standard
J 0
(-6075 2975);
DISPLAY 0.723404 (-6075 2975);
PAINT MONO (-6075 2975);
DISPLAY INVISIBLE (-6075 2975);
FORCEPROP 1 LAST BODY_TYPE PLUMBING
J 0
(-6075 3025);
DISPLAY 0.872340 (-6075 3025);
PAINT GREEN (-6075 3025);
DISPLAY INVISIBLE (-6075 3025);
FORCEPROP 1 LAST HDL_TAP TRUE
J 0
(-5750 2850);
DISPLAY 0.872340 (-5750 2850);
DISPLAY INVISIBLE (-5750 2850);
FORCEPROP 1 LAST PATH I48
J 0
(-6077 2975);
DISPLAY 0.872340 (-6077 2975);
PAINT GREEN (-6077 2975);
DISPLAY INVISIBLE (-6077 2975);
FORCEADD TAP..1
(-6075 3025);
FORCEPROP 3 LASTPIN (-6125 3025) SIG_NAME M_B_CPU1_SB_DQ<14>
J 0
(-6115 3035);
DISPLAY 0.659574 (-6115 3035);
PAINT MONO (-6115 3035);
DISPLAY INVISIBLE (-6115 3035);
FORCEPROP 1 LASTPIN (-6125 3025) BN 14
J 0
(-6137 3033);
DISPLAY 0.489362 (-6137 3033);
PAINT GREEN (-6137 3033);
FORCEPROP 2 LAST CDS_LIB mstr_standard
J 0
(-6075 3025);
DISPLAY 0.723404 (-6075 3025);
PAINT MONO (-6075 3025);
DISPLAY INVISIBLE (-6075 3025);
FORCEPROP 1 LAST BODY_TYPE PLUMBING
J 0
(-6075 3075);
DISPLAY 0.872340 (-6075 3075);
PAINT GREEN (-6075 3075);
DISPLAY INVISIBLE (-6075 3075);
FORCEPROP 1 LAST HDL_TAP TRUE
J 0
(-5750 2900);
DISPLAY 0.872340 (-5750 2900);
DISPLAY INVISIBLE (-5750 2900);
FORCEPROP 1 LAST PATH I49
J 0
(-6077 3025);
DISPLAY 0.872340 (-6077 3025);
PAINT GREEN (-6077 3025);
DISPLAY INVISIBLE (-6077 3025);
FORCEADD TAP..1
(-6075 2925);
FORCEPROP 3 LASTPIN (-6125 2925) SIG_NAME M_B_CPU1_SB_DQ<12>
J 0
(-6115 2935);
DISPLAY 0.659574 (-6115 2935);
PAINT MONO (-6115 2935);
DISPLAY INVISIBLE (-6115 2935);
FORCEPROP 1 LASTPIN (-6125 2925) BN 12
J 0
(-6137 2933);
DISPLAY 0.489362 (-6137 2933);
PAINT GREEN (-6137 2933);
FORCEPROP 2 LAST CDS_LIB mstr_standard
J 0
(-6075 2925);
DISPLAY 0.723404 (-6075 2925);
PAINT MONO (-6075 2925);
DISPLAY INVISIBLE (-6075 2925);
FORCEPROP 1 LAST BODY_TYPE PLUMBING
J 0
(-6075 2975);
DISPLAY 0.872340 (-6075 2975);
PAINT GREEN (-6075 2975);
DISPLAY INVISIBLE (-6075 2975);
FORCEPROP 1 LAST HDL_TAP TRUE
J 0
(-5750 2800);
DISPLAY 0.872340 (-5750 2800);
DISPLAY INVISIBLE (-5750 2800);
FORCEPROP 1 LAST PATH I50
J 0
(-6077 2925);
DISPLAY 0.872340 (-6077 2925);
PAINT GREEN (-6077 2925);
DISPLAY INVISIBLE (-6077 2925);
FORCEADD TAP..1
(-6075 2875);
FORCEPROP 3 LASTPIN (-6125 2875) SIG_NAME M_B_CPU1_SB_DQ<11>
J 0
(-6115 2885);
DISPLAY 0.659574 (-6115 2885);
PAINT MONO (-6115 2885);
DISPLAY INVISIBLE (-6115 2885);
FORCEPROP 1 LASTPIN (-6125 2875) BN 11
J 0
(-6137 2883);
DISPLAY 0.489362 (-6137 2883);
PAINT GREEN (-6137 2883);
FORCEPROP 2 LAST CDS_LIB mstr_standard
J 0
(-6075 2875);
DISPLAY 0.723404 (-6075 2875);
PAINT MONO (-6075 2875);
DISPLAY INVISIBLE (-6075 2875);
FORCEPROP 1 LAST BODY_TYPE PLUMBING
J 0
(-6075 2925);
DISPLAY 0.872340 (-6075 2925);
PAINT GREEN (-6075 2925);
DISPLAY INVISIBLE (-6075 2925);
FORCEPROP 1 LAST HDL_TAP TRUE
J 0
(-5750 2750);
DISPLAY 0.872340 (-5750 2750);
DISPLAY INVISIBLE (-5750 2750);
FORCEPROP 1 LAST PATH I51
J 0
(-6077 2875);
DISPLAY 0.872340 (-6077 2875);
PAINT GREEN (-6077 2875);
DISPLAY INVISIBLE (-6077 2875);
FORCEADD TAP..1
(-6075 2825);
FORCEPROP 3 LASTPIN (-6125 2825) SIG_NAME M_B_CPU1_SB_DQ<10>
J 0
(-6115 2835);
DISPLAY 0.659574 (-6115 2835);
PAINT MONO (-6115 2835);
DISPLAY INVISIBLE (-6115 2835);
FORCEPROP 1 LASTPIN (-6125 2825) BN 10
J 0
(-6137 2833);
DISPLAY 0.489362 (-6137 2833);
PAINT GREEN (-6137 2833);
FORCEPROP 2 LAST CDS_LIB mstr_standard
J 0
(-6075 2825);
DISPLAY 0.723404 (-6075 2825);
PAINT MONO (-6075 2825);
DISPLAY INVISIBLE (-6075 2825);
FORCEPROP 1 LAST BODY_TYPE PLUMBING
J 0
(-6075 2875);
DISPLAY 0.872340 (-6075 2875);
PAINT GREEN (-6075 2875);
DISPLAY INVISIBLE (-6075 2875);
FORCEPROP 1 LAST HDL_TAP TRUE
J 0
(-5750 2700);
DISPLAY 0.872340 (-5750 2700);
DISPLAY INVISIBLE (-5750 2700);
FORCEPROP 1 LAST PATH I52
J 0
(-6077 2825);
DISPLAY 0.872340 (-6077 2825);
PAINT GREEN (-6077 2825);
DISPLAY INVISIBLE (-6077 2825);
FORCEADD TAP..1
(-6075 3075);
FORCEPROP 3 LASTPIN (-6125 3075) SIG_NAME M_B_CPU1_SB_DQ<15>
J 0
(-6115 3085);
DISPLAY 0.659574 (-6115 3085);
PAINT MONO (-6115 3085);
DISPLAY INVISIBLE (-6115 3085);
FORCEPROP 1 LASTPIN (-6125 3075) BN 15
J 0
(-6137 3083);
DISPLAY 0.489362 (-6137 3083);
PAINT GREEN (-6137 3083);
FORCEPROP 2 LAST CDS_LIB mstr_standard
J 0
(-6075 3075);
DISPLAY 0.723404 (-6075 3075);
PAINT MONO (-6075 3075);
DISPLAY INVISIBLE (-6075 3075);
FORCEPROP 1 LAST BODY_TYPE PLUMBING
J 0
(-6075 3125);
DISPLAY 0.872340 (-6075 3125);
PAINT GREEN (-6075 3125);
DISPLAY INVISIBLE (-6075 3125);
FORCEPROP 1 LAST HDL_TAP TRUE
J 0
(-5750 2950);
DISPLAY 0.872340 (-5750 2950);
DISPLAY INVISIBLE (-5750 2950);
FORCEPROP 1 LAST PATH I53
J 0
(-6077 3075);
DISPLAY 0.872340 (-6077 3075);
PAINT GREEN (-6077 3075);
DISPLAY INVISIBLE (-6077 3075);
FORCEADD TAP..1
(-6075 3175);
FORCEPROP 3 LASTPIN (-6125 3175) SIG_NAME M_B_CPU1_SB_DQ<17>
J 0
(-6115 3185);
DISPLAY 0.659574 (-6115 3185);
PAINT MONO (-6115 3185);
DISPLAY INVISIBLE (-6115 3185);
FORCEPROP 1 LASTPIN (-6125 3175) BN 17
J 0
(-6137 3183);
DISPLAY 0.489362 (-6137 3183);
PAINT GREEN (-6137 3183);
FORCEPROP 2 LAST CDS_LIB mstr_standard
J 0
(-6075 3175);
DISPLAY 0.723404 (-6075 3175);
PAINT MONO (-6075 3175);
DISPLAY INVISIBLE (-6075 3175);
FORCEPROP 1 LAST BODY_TYPE PLUMBING
J 0
(-6075 3225);
DISPLAY 0.872340 (-6075 3225);
PAINT GREEN (-6075 3225);
DISPLAY INVISIBLE (-6075 3225);
FORCEPROP 1 LAST HDL_TAP TRUE
J 0
(-5750 3050);
DISPLAY 0.872340 (-5750 3050);
DISPLAY INVISIBLE (-5750 3050);
FORCEPROP 1 LAST PATH I54
J 0
(-6077 3175);
DISPLAY 0.872340 (-6077 3175);
PAINT GREEN (-6077 3175);
DISPLAY INVISIBLE (-6077 3175);
FORCEADD TAP..1
(-6075 3125);
FORCEPROP 3 LASTPIN (-6125 3125) SIG_NAME M_B_CPU1_SB_DQ<16>
J 0
(-6115 3135);
DISPLAY 0.659574 (-6115 3135);
PAINT MONO (-6115 3135);
DISPLAY INVISIBLE (-6115 3135);
FORCEPROP 1 LASTPIN (-6125 3125) BN 16
J 0
(-6137 3133);
DISPLAY 0.489362 (-6137 3133);
PAINT GREEN (-6137 3133);
FORCEPROP 2 LAST CDS_LIB mstr_standard
J 0
(-6075 3125);
DISPLAY 0.723404 (-6075 3125);
PAINT MONO (-6075 3125);
DISPLAY INVISIBLE (-6075 3125);
FORCEPROP 1 LAST BODY_TYPE PLUMBING
J 0
(-6075 3175);
DISPLAY 0.872340 (-6075 3175);
PAINT GREEN (-6075 3175);
DISPLAY INVISIBLE (-6075 3175);
FORCEPROP 1 LAST HDL_TAP TRUE
J 0
(-5750 3000);
DISPLAY 0.872340 (-5750 3000);
DISPLAY INVISIBLE (-5750 3000);
FORCEPROP 1 LAST PATH I55
J 0
(-6077 3125);
DISPLAY 0.872340 (-6077 3125);
PAINT GREEN (-6077 3125);
DISPLAY INVISIBLE (-6077 3125);
FORCEADD TAP..1
(-6075 3225);
FORCEPROP 3 LASTPIN (-6125 3225) SIG_NAME M_B_CPU1_SB_DQ<18>
J 0
(-6115 3235);
DISPLAY 0.659574 (-6115 3235);
PAINT MONO (-6115 3235);
DISPLAY INVISIBLE (-6115 3235);
FORCEPROP 1 LASTPIN (-6125 3225) BN 18
J 0
(-6137 3233);
DISPLAY 0.489362 (-6137 3233);
PAINT GREEN (-6137 3233);
FORCEPROP 2 LAST CDS_LIB mstr_standard
J 0
(-6075 3225);
DISPLAY 0.723404 (-6075 3225);
PAINT MONO (-6075 3225);
DISPLAY INVISIBLE (-6075 3225);
FORCEPROP 1 LAST BODY_TYPE PLUMBING
J 0
(-6075 3275);
DISPLAY 0.872340 (-6075 3275);
PAINT GREEN (-6075 3275);
DISPLAY INVISIBLE (-6075 3275);
FORCEPROP 1 LAST HDL_TAP TRUE
J 0
(-5750 3100);
DISPLAY 0.872340 (-5750 3100);
DISPLAY INVISIBLE (-5750 3100);
FORCEPROP 1 LAST PATH I56
J 0
(-6077 3225);
DISPLAY 0.872340 (-6077 3225);
PAINT GREEN (-6077 3225);
DISPLAY INVISIBLE (-6077 3225);
FORCEADD TAP..1
(-6075 3275);
FORCEPROP 3 LASTPIN (-6125 3275) SIG_NAME M_B_CPU1_SB_DQ<19>
J 0
(-6115 3285);
DISPLAY 0.659574 (-6115 3285);
PAINT MONO (-6115 3285);
DISPLAY INVISIBLE (-6115 3285);
FORCEPROP 1 LASTPIN (-6125 3275) BN 19
J 0
(-6137 3283);
DISPLAY 0.489362 (-6137 3283);
PAINT GREEN (-6137 3283);
FORCEPROP 2 LAST CDS_LIB mstr_standard
J 0
(-6075 3275);
DISPLAY 0.723404 (-6075 3275);
PAINT MONO (-6075 3275);
DISPLAY INVISIBLE (-6075 3275);
FORCEPROP 1 LAST BODY_TYPE PLUMBING
J 0
(-6075 3325);
DISPLAY 0.872340 (-6075 3325);
PAINT GREEN (-6075 3325);
DISPLAY INVISIBLE (-6075 3325);
FORCEPROP 1 LAST HDL_TAP TRUE
J 0
(-5750 3150);
DISPLAY 0.872340 (-5750 3150);
DISPLAY INVISIBLE (-5750 3150);
FORCEPROP 1 LAST PATH I57
J 0
(-6077 3275);
DISPLAY 0.872340 (-6077 3275);
PAINT GREEN (-6077 3275);
DISPLAY INVISIBLE (-6077 3275);
FORCEADD TAP..1
(-6075 3325);
FORCEPROP 3 LASTPIN (-6125 3325) SIG_NAME M_B_CPU1_SB_DQ<20>
J 0
(-6115 3335);
DISPLAY 0.659574 (-6115 3335);
PAINT MONO (-6115 3335);
DISPLAY INVISIBLE (-6115 3335);
FORCEPROP 1 LASTPIN (-6125 3325) BN 20
J 0
(-6137 3333);
DISPLAY 0.489362 (-6137 3333);
PAINT GREEN (-6137 3333);
FORCEPROP 2 LAST CDS_LIB mstr_standard
J 0
(-6075 3325);
DISPLAY 0.723404 (-6075 3325);
PAINT MONO (-6075 3325);
DISPLAY INVISIBLE (-6075 3325);
FORCEPROP 1 LAST BODY_TYPE PLUMBING
J 0
(-6075 3375);
DISPLAY 0.872340 (-6075 3375);
PAINT GREEN (-6075 3375);
DISPLAY INVISIBLE (-6075 3375);
FORCEPROP 1 LAST HDL_TAP TRUE
J 0
(-5750 3200);
DISPLAY 0.872340 (-5750 3200);
DISPLAY INVISIBLE (-5750 3200);
FORCEPROP 1 LAST PATH I58
J 0
(-6077 3325);
DISPLAY 0.872340 (-6077 3325);
PAINT GREEN (-6077 3325);
DISPLAY INVISIBLE (-6077 3325);
FORCEADD TAP..1
(-6075 3475);
FORCEPROP 3 LASTPIN (-6125 3475) SIG_NAME M_B_CPU1_SB_DQ<23>
J 0
(-6115 3485);
DISPLAY 0.659574 (-6115 3485);
PAINT MONO (-6115 3485);
DISPLAY INVISIBLE (-6115 3485);
FORCEPROP 1 LASTPIN (-6125 3475) BN 23
J 0
(-6137 3483);
DISPLAY 0.489362 (-6137 3483);
PAINT GREEN (-6137 3483);
FORCEPROP 2 LAST CDS_LIB mstr_standard
J 0
(-6075 3475);
DISPLAY 0.723404 (-6075 3475);
PAINT MONO (-6075 3475);
DISPLAY INVISIBLE (-6075 3475);
FORCEPROP 1 LAST BODY_TYPE PLUMBING
J 0
(-6075 3525);
DISPLAY 0.872340 (-6075 3525);
PAINT GREEN (-6075 3525);
DISPLAY INVISIBLE (-6075 3525);
FORCEPROP 1 LAST HDL_TAP TRUE
J 0
(-5750 3350);
DISPLAY 0.872340 (-5750 3350);
DISPLAY INVISIBLE (-5750 3350);
FORCEPROP 1 LAST PATH I59
J 0
(-6077 3475);
DISPLAY 0.872340 (-6077 3475);
PAINT GREEN (-6077 3475);
DISPLAY INVISIBLE (-6077 3475);
FORCEADD OFFPAGE..5
(-8375 2125);
FORCEPROP 2 LAST $XR0 38 
J 0
(-8629 2125);
DISPLAY 0.638298 (-8629 2125);
PAINT MONO (-8629 2125);
FORCEPROP 2 LAST PATH I6
J 0
(-8575 2175);
DISPLAY 1.021277 (-8575 2175);
DISPLAY INVISIBLE (-8575 2175);
FORCEPROP 1 LAST COMMENT_BODY TRUE
J 0
(-8275 2050);
DISPLAY 0.872340 (-8275 2050);
PAINT GREEN (-8275 2050);
DISPLAY INVISIBLE (-8275 2050);
FORCEPROP 1 LAST OFFPAGE TRUE
J 0
(-8050 2000);
DISPLAY 0.872340 (-8050 2000);
PAINT GREEN (-8050 2000);
DISPLAY INVISIBLE (-8050 2000);
FORCEPROP 2 LAST CDS_LIB mstr_standard
J 0
(-8375 2125);
DISPLAY 0.808511 (-8375 2125);
DISPLAY INVISIBLE (-8375 2125);
FORCEADD TAP..1
(-6075 3525);
FORCEPROP 3 LASTPIN (-6125 3525) SIG_NAME M_B_CPU1_SB_DQ<24>
J 0
(-6115 3535);
DISPLAY 0.659574 (-6115 3535);
PAINT MONO (-6115 3535);
DISPLAY INVISIBLE (-6115 3535);
FORCEPROP 1 LASTPIN (-6125 3525) BN 24
J 0
(-6137 3533);
DISPLAY 0.489362 (-6137 3533);
PAINT GREEN (-6137 3533);
FORCEPROP 2 LAST CDS_LIB mstr_standard
J 0
(-6075 3525);
DISPLAY 0.723404 (-6075 3525);
PAINT MONO (-6075 3525);
DISPLAY INVISIBLE (-6075 3525);
FORCEPROP 1 LAST BODY_TYPE PLUMBING
J 0
(-6075 3575);
DISPLAY 0.872340 (-6075 3575);
PAINT GREEN (-6075 3575);
DISPLAY INVISIBLE (-6075 3575);
FORCEPROP 1 LAST HDL_TAP TRUE
J 0
(-5750 3400);
DISPLAY 0.872340 (-5750 3400);
DISPLAY INVISIBLE (-5750 3400);
FORCEPROP 1 LAST PATH I60
J 0
(-6077 3525);
DISPLAY 0.872340 (-6077 3525);
PAINT GREEN (-6077 3525);
DISPLAY INVISIBLE (-6077 3525);
FORCEADD TAP..1
(-6075 3575);
FORCEPROP 3 LASTPIN (-6125 3575) SIG_NAME M_B_CPU1_SB_DQ<25>
J 0
(-6115 3585);
DISPLAY 0.659574 (-6115 3585);
PAINT MONO (-6115 3585);
DISPLAY INVISIBLE (-6115 3585);
FORCEPROP 1 LASTPIN (-6125 3575) BN 25
J 0
(-6137 3583);
DISPLAY 0.489362 (-6137 3583);
PAINT GREEN (-6137 3583);
FORCEPROP 2 LAST CDS_LIB mstr_standard
J 0
(-6075 3575);
DISPLAY 0.723404 (-6075 3575);
PAINT MONO (-6075 3575);
DISPLAY INVISIBLE (-6075 3575);
FORCEPROP 1 LAST BODY_TYPE PLUMBING
J 0
(-6075 3625);
DISPLAY 0.872340 (-6075 3625);
PAINT GREEN (-6075 3625);
DISPLAY INVISIBLE (-6075 3625);
FORCEPROP 1 LAST HDL_TAP TRUE
J 0
(-5750 3450);
DISPLAY 0.872340 (-5750 3450);
DISPLAY INVISIBLE (-5750 3450);
FORCEPROP 1 LAST PATH I61
J 0
(-6077 3575);
DISPLAY 0.872340 (-6077 3575);
PAINT GREEN (-6077 3575);
DISPLAY INVISIBLE (-6077 3575);
FORCEADD TAP..1
(-6075 3425);
FORCEPROP 3 LASTPIN (-6125 3425) SIG_NAME M_B_CPU1_SB_DQ<22>
J 0
(-6115 3435);
DISPLAY 0.659574 (-6115 3435);
PAINT MONO (-6115 3435);
DISPLAY INVISIBLE (-6115 3435);
FORCEPROP 1 LASTPIN (-6125 3425) BN 22
J 0
(-6137 3433);
DISPLAY 0.489362 (-6137 3433);
PAINT GREEN (-6137 3433);
FORCEPROP 2 LAST CDS_LIB mstr_standard
J 0
(-6075 3425);
DISPLAY 0.723404 (-6075 3425);
PAINT MONO (-6075 3425);
DISPLAY INVISIBLE (-6075 3425);
FORCEPROP 1 LAST BODY_TYPE PLUMBING
J 0
(-6075 3475);
DISPLAY 0.872340 (-6075 3475);
PAINT GREEN (-6075 3475);
DISPLAY INVISIBLE (-6075 3475);
FORCEPROP 1 LAST HDL_TAP TRUE
J 0
(-5750 3300);
DISPLAY 0.872340 (-5750 3300);
DISPLAY INVISIBLE (-5750 3300);
FORCEPROP 1 LAST PATH I62
J 0
(-6077 3425);
DISPLAY 0.872340 (-6077 3425);
PAINT GREEN (-6077 3425);
DISPLAY INVISIBLE (-6077 3425);
FORCEADD TAP..1
(-6075 3375);
FORCEPROP 3 LASTPIN (-6125 3375) SIG_NAME M_B_CPU1_SB_DQ<21>
J 0
(-6115 3385);
DISPLAY 0.659574 (-6115 3385);
PAINT MONO (-6115 3385);
DISPLAY INVISIBLE (-6115 3385);
FORCEPROP 1 LASTPIN (-6125 3375) BN 21
J 0
(-6137 3383);
DISPLAY 0.489362 (-6137 3383);
PAINT GREEN (-6137 3383);
FORCEPROP 2 LAST CDS_LIB mstr_standard
J 0
(-6075 3375);
DISPLAY 0.723404 (-6075 3375);
PAINT MONO (-6075 3375);
DISPLAY INVISIBLE (-6075 3375);
FORCEPROP 1 LAST BODY_TYPE PLUMBING
J 0
(-6075 3425);
DISPLAY 0.872340 (-6075 3425);
PAINT GREEN (-6075 3425);
DISPLAY INVISIBLE (-6075 3425);
FORCEPROP 1 LAST HDL_TAP TRUE
J 0
(-5750 3250);
DISPLAY 0.872340 (-5750 3250);
DISPLAY INVISIBLE (-5750 3250);
FORCEPROP 1 LAST PATH I63
J 0
(-6077 3375);
DISPLAY 0.872340 (-6077 3375);
PAINT GREEN (-6077 3375);
DISPLAY INVISIBLE (-6077 3375);
FORCEADD TAP..1
(-6075 3725);
FORCEPROP 3 LASTPIN (-6125 3725) SIG_NAME M_B_CPU1_SB_DQ<28>
J 0
(-6115 3735);
DISPLAY 0.659574 (-6115 3735);
PAINT MONO (-6115 3735);
DISPLAY INVISIBLE (-6115 3735);
FORCEPROP 1 LASTPIN (-6125 3725) BN 28
J 0
(-6137 3733);
DISPLAY 0.489362 (-6137 3733);
PAINT GREEN (-6137 3733);
FORCEPROP 2 LAST CDS_LIB mstr_standard
J 0
(-6075 3725);
DISPLAY 0.723404 (-6075 3725);
PAINT MONO (-6075 3725);
DISPLAY INVISIBLE (-6075 3725);
FORCEPROP 1 LAST BODY_TYPE PLUMBING
J 0
(-6075 3775);
DISPLAY 0.872340 (-6075 3775);
PAINT GREEN (-6075 3775);
DISPLAY INVISIBLE (-6075 3775);
FORCEPROP 1 LAST HDL_TAP TRUE
J 0
(-5750 3600);
DISPLAY 0.872340 (-5750 3600);
DISPLAY INVISIBLE (-5750 3600);
FORCEPROP 1 LAST PATH I64
J 0
(-6077 3725);
DISPLAY 0.872340 (-6077 3725);
PAINT GREEN (-6077 3725);
DISPLAY INVISIBLE (-6077 3725);
FORCEADD TAP..1
(-6075 3825);
FORCEPROP 3 LASTPIN (-6125 3825) SIG_NAME M_B_CPU1_SB_DQ<30>
J 0
(-6115 3835);
DISPLAY 0.659574 (-6115 3835);
PAINT MONO (-6115 3835);
DISPLAY INVISIBLE (-6115 3835);
FORCEPROP 1 LASTPIN (-6125 3825) BN 30
J 0
(-6137 3833);
DISPLAY 0.489362 (-6137 3833);
PAINT GREEN (-6137 3833);
FORCEPROP 2 LAST CDS_LIB mstr_standard
J 0
(-6075 3825);
DISPLAY 0.723404 (-6075 3825);
PAINT MONO (-6075 3825);
DISPLAY INVISIBLE (-6075 3825);
FORCEPROP 1 LAST BODY_TYPE PLUMBING
J 0
(-6075 3875);
DISPLAY 0.872340 (-6075 3875);
PAINT GREEN (-6075 3875);
DISPLAY INVISIBLE (-6075 3875);
FORCEPROP 1 LAST HDL_TAP TRUE
J 0
(-5750 3700);
DISPLAY 0.872340 (-5750 3700);
DISPLAY INVISIBLE (-5750 3700);
FORCEPROP 1 LAST PATH I65
J 0
(-6077 3825);
DISPLAY 0.872340 (-6077 3825);
PAINT GREEN (-6077 3825);
DISPLAY INVISIBLE (-6077 3825);
FORCEADD TAP..1
(-6075 3775);
FORCEPROP 3 LASTPIN (-6125 3775) SIG_NAME M_B_CPU1_SB_DQ<29>
J 0
(-6115 3785);
DISPLAY 0.659574 (-6115 3785);
PAINT MONO (-6115 3785);
DISPLAY INVISIBLE (-6115 3785);
FORCEPROP 1 LASTPIN (-6125 3775) BN 29
J 0
(-6137 3783);
DISPLAY 0.489362 (-6137 3783);
PAINT GREEN (-6137 3783);
FORCEPROP 2 LAST CDS_LIB mstr_standard
J 0
(-6075 3775);
DISPLAY 0.723404 (-6075 3775);
PAINT MONO (-6075 3775);
DISPLAY INVISIBLE (-6075 3775);
FORCEPROP 1 LAST BODY_TYPE PLUMBING
J 0
(-6075 3825);
DISPLAY 0.872340 (-6075 3825);
PAINT GREEN (-6075 3825);
DISPLAY INVISIBLE (-6075 3825);
FORCEPROP 1 LAST HDL_TAP TRUE
J 0
(-5750 3650);
DISPLAY 0.872340 (-5750 3650);
DISPLAY INVISIBLE (-5750 3650);
FORCEPROP 1 LAST PATH I66
J 0
(-6077 3775);
DISPLAY 0.872340 (-6077 3775);
PAINT GREEN (-6077 3775);
DISPLAY INVISIBLE (-6077 3775);
FORCEADD TAP..1
(-6075 3675);
FORCEPROP 3 LASTPIN (-6125 3675) SIG_NAME M_B_CPU1_SB_DQ<27>
J 0
(-6115 3685);
DISPLAY 0.659574 (-6115 3685);
PAINT MONO (-6115 3685);
DISPLAY INVISIBLE (-6115 3685);
FORCEPROP 1 LASTPIN (-6125 3675) BN 27
J 0
(-6137 3683);
DISPLAY 0.489362 (-6137 3683);
PAINT GREEN (-6137 3683);
FORCEPROP 2 LAST CDS_LIB mstr_standard
J 0
(-6075 3675);
DISPLAY 0.723404 (-6075 3675);
PAINT MONO (-6075 3675);
DISPLAY INVISIBLE (-6075 3675);
FORCEPROP 1 LAST BODY_TYPE PLUMBING
J 0
(-6075 3725);
DISPLAY 0.872340 (-6075 3725);
PAINT GREEN (-6075 3725);
DISPLAY INVISIBLE (-6075 3725);
FORCEPROP 1 LAST HDL_TAP TRUE
J 0
(-5750 3550);
DISPLAY 0.872340 (-5750 3550);
DISPLAY INVISIBLE (-5750 3550);
FORCEPROP 1 LAST PATH I67
J 0
(-6077 3675);
DISPLAY 0.872340 (-6077 3675);
PAINT GREEN (-6077 3675);
DISPLAY INVISIBLE (-6077 3675);
FORCEADD TAP..1
(-6075 3625);
FORCEPROP 3 LASTPIN (-6125 3625) SIG_NAME M_B_CPU1_SB_DQ<26>
J 0
(-6115 3635);
DISPLAY 0.659574 (-6115 3635);
PAINT MONO (-6115 3635);
DISPLAY INVISIBLE (-6115 3635);
FORCEPROP 1 LASTPIN (-6125 3625) BN 26
J 0
(-6137 3633);
DISPLAY 0.489362 (-6137 3633);
PAINT GREEN (-6137 3633);
FORCEPROP 2 LAST CDS_LIB mstr_standard
J 0
(-6075 3625);
DISPLAY 0.723404 (-6075 3625);
PAINT MONO (-6075 3625);
DISPLAY INVISIBLE (-6075 3625);
FORCEPROP 1 LAST BODY_TYPE PLUMBING
J 0
(-6075 3675);
DISPLAY 0.872340 (-6075 3675);
PAINT GREEN (-6075 3675);
DISPLAY INVISIBLE (-6075 3675);
FORCEPROP 1 LAST HDL_TAP TRUE
J 0
(-5750 3500);
DISPLAY 0.872340 (-5750 3500);
DISPLAY INVISIBLE (-5750 3500);
FORCEPROP 1 LAST PATH I68
J 0
(-6077 3625);
DISPLAY 0.872340 (-6077 3625);
PAINT GREEN (-6077 3625);
DISPLAY INVISIBLE (-6077 3625);
FORCEADD TAP..1
(-6075 3875);
FORCEPROP 3 LASTPIN (-6125 3875) SIG_NAME M_B_CPU1_SB_DQ<31>
J 0
(-6115 3885);
DISPLAY 0.659574 (-6115 3885);
PAINT MONO (-6115 3885);
DISPLAY INVISIBLE (-6115 3885);
FORCEPROP 1 LASTPIN (-6125 3875) BN 31
J 0
(-6137 3883);
DISPLAY 0.489362 (-6137 3883);
PAINT GREEN (-6137 3883);
FORCEPROP 2 LAST CDS_LIB mstr_standard
J 0
(-6075 3875);
DISPLAY 0.723404 (-6075 3875);
PAINT MONO (-6075 3875);
DISPLAY INVISIBLE (-6075 3875);
FORCEPROP 1 LAST BODY_TYPE PLUMBING
J 0
(-6075 3925);
DISPLAY 0.872340 (-6075 3925);
PAINT GREEN (-6075 3925);
DISPLAY INVISIBLE (-6075 3925);
FORCEPROP 1 LAST HDL_TAP TRUE
J 0
(-5750 3750);
DISPLAY 0.872340 (-5750 3750);
DISPLAY INVISIBLE (-5750 3750);
FORCEPROP 1 LAST PATH I69
J 0
(-6077 3875);
DISPLAY 0.872340 (-6077 3875);
PAINT GREEN (-6077 3875);
DISPLAY INVISIBLE (-6077 3875);
FORCEADD VCC_CORE..1
(-8625 3550);
FORCEPROP 3 LASTPIN (-8625 3500) SIG_NAME P3V3_STBY\g
J 0
(-8615 3510);
DISPLAY 0.659574 (-8615 3510);
PAINT MONO (-8615 3510);
DISPLAY INVISIBLE (-8615 3510);
FORCEPROP 1 LAST HDL_POWER P3V3_STBY
J 1
(-8625 3600);
DISPLAY 0.489362 (-8625 3600);
PAINT GREEN (-8625 3600);
FORCEPROP 2 LAST CDS_LIB mstr_symbols
J 0
(-8625 3550);
PAINT MONO (-8625 3550);
DISPLAY INVISIBLE (-8625 3550);
FORCEPROP 1 LAST PATH I7
J 0
(-8575 3575);
DISPLAY 0.872340 (-8575 3575);
PAINT AQUA (-8575 3575);
DISPLAY INVISIBLE (-8575 3575);
FORCEPROP 0 LAST VOLTAGE 3.3
J 0
(-8900 3700);
DISPLAY 1.021277 (-8900 3700);
PAINT SKYBLUE (-8900 3700);
DISPLAY INVISIBLE (-8900 3700);
FORCEPROP 2 LAST ROOM PVCCINFAON_CPU1_CTRL
J 0
(-8625 3650);
DISPLAY 0.808511 (-8625 3650);
PAINT RED (-8625 3650);
DISPLAY INVISIBLE (-8625 3650);
FORCEADD TAP..1
(-6075 4025);
FORCEPROP 3 LASTPIN (-6125 4025) SIG_NAME M_B_CPU1_SA_DQ<1>
J 0
(-6115 4035);
DISPLAY 0.659574 (-6115 4035);
PAINT MONO (-6115 4035);
DISPLAY INVISIBLE (-6115 4035);
FORCEPROP 1 LASTPIN (-6125 4025) BN 1
J 0
(-6137 4033);
DISPLAY 0.489362 (-6137 4033);
PAINT GREEN (-6137 4033);
FORCEPROP 2 LAST CDS_LIB mstr_standard
J 0
(-6075 4025);
DISPLAY 0.723404 (-6075 4025);
PAINT MONO (-6075 4025);
DISPLAY INVISIBLE (-6075 4025);
FORCEPROP 1 LAST BODY_TYPE PLUMBING
J 0
(-6075 4075);
DISPLAY 0.872340 (-6075 4075);
PAINT GREEN (-6075 4075);
DISPLAY INVISIBLE (-6075 4075);
FORCEPROP 1 LAST HDL_TAP TRUE
J 0
(-5750 3900);
DISPLAY 0.872340 (-5750 3900);
DISPLAY INVISIBLE (-5750 3900);
FORCEPROP 1 LAST PATH I70
J 0
(-6077 4025);
DISPLAY 0.872340 (-6077 4025);
PAINT GREEN (-6077 4025);
DISPLAY INVISIBLE (-6077 4025);
FORCEADD TAP..1
(-6075 4075);
FORCEPROP 3 LASTPIN (-6125 4075) SIG_NAME M_B_CPU1_SA_DQ<2>
J 0
(-6115 4085);
DISPLAY 0.659574 (-6115 4085);
PAINT MONO (-6115 4085);
DISPLAY INVISIBLE (-6115 4085);
FORCEPROP 1 LASTPIN (-6125 4075) BN 2
J 0
(-6137 4083);
DISPLAY 0.489362 (-6137 4083);
PAINT GREEN (-6137 4083);
FORCEPROP 2 LAST CDS_LIB mstr_standard
J 0
(-6075 4075);
DISPLAY 0.723404 (-6075 4075);
PAINT MONO (-6075 4075);
DISPLAY INVISIBLE (-6075 4075);
FORCEPROP 1 LAST BODY_TYPE PLUMBING
J 0
(-6075 4125);
DISPLAY 0.872340 (-6075 4125);
PAINT GREEN (-6075 4125);
DISPLAY INVISIBLE (-6075 4125);
FORCEPROP 1 LAST HDL_TAP TRUE
J 0
(-5750 3950);
DISPLAY 0.872340 (-5750 3950);
DISPLAY INVISIBLE (-5750 3950);
FORCEPROP 1 LAST PATH I71
J 0
(-6077 4075);
DISPLAY 0.872340 (-6077 4075);
PAINT GREEN (-6077 4075);
DISPLAY INVISIBLE (-6077 4075);
FORCEADD TAP..1
(-6075 3975);
FORCEPROP 3 LASTPIN (-6125 3975) SIG_NAME M_B_CPU1_SA_DQ<0>
J 0
(-6115 3985);
DISPLAY 0.659574 (-6115 3985);
PAINT MONO (-6115 3985);
DISPLAY INVISIBLE (-6115 3985);
FORCEPROP 1 LASTPIN (-6125 3975) BN 0
J 0
(-6137 3983);
DISPLAY 0.489362 (-6137 3983);
PAINT GREEN (-6137 3983);
FORCEPROP 2 LAST CDS_LIB mstr_standard
J 0
(-6075 3975);
DISPLAY 0.723404 (-6075 3975);
PAINT MONO (-6075 3975);
DISPLAY INVISIBLE (-6075 3975);
FORCEPROP 1 LAST BODY_TYPE PLUMBING
J 0
(-6075 4025);
DISPLAY 0.872340 (-6075 4025);
PAINT GREEN (-6075 4025);
DISPLAY INVISIBLE (-6075 4025);
FORCEPROP 1 LAST HDL_TAP TRUE
J 0
(-5750 3850);
DISPLAY 0.872340 (-5750 3850);
DISPLAY INVISIBLE (-5750 3850);
FORCEPROP 1 LAST PATH I72
J 0
(-6077 3975);
DISPLAY 0.872340 (-6077 3975);
PAINT GREEN (-6077 3975);
DISPLAY INVISIBLE (-6077 3975);
FORCEADD OFFPAGE..3
(-5325 3925);
FORCEPROP 2 LAST $XR0 38 
J 0
(-5111 3925);
DISPLAY 0.638298 (-5111 3925);
PAINT MONO (-5111 3925);
FORCEPROP 2 LAST PATH I79
J 0
(-5100 3975);
DISPLAY 1.021277 (-5100 3975);
DISPLAY INVISIBLE (-5100 3975);
FORCEPROP 1 LAST COMMENT_BODY TRUE
J 0
(-5375 3825);
DISPLAY 0.872340 (-5375 3825);
PAINT GREEN (-5375 3825);
DISPLAY INVISIBLE (-5375 3825);
FORCEPROP 1 LAST OFFPAGE TRUE
J 0
(-5000 3800);
DISPLAY 0.872340 (-5000 3800);
PAINT GREEN (-5000 3800);
DISPLAY INVISIBLE (-5000 3800);
FORCEPROP 2 LAST CDS_LIB mstr_standard
J 0
(-5325 3925);
DISPLAY 0.723404 (-5325 3925);
PAINT MONO (-5325 3925);
DISPLAY INVISIBLE (-5325 3925);
FORCEADD OFFPAGE..6
(-8375 3725);
FORCEPROP 2 LAST $XR0 38 
J 0
(-8654 3725);
DISPLAY 0.638298 (-8654 3725);
PAINT MONO (-8654 3725);
FORCEPROP 2 LAST PATH I8
J 0
(-8600 3775);
DISPLAY 1.021277 (-8600 3775);
DISPLAY INVISIBLE (-8600 3775);
FORCEPROP 1 LAST COMMENT_BODY TRUE
J 0
(-8275 3650);
DISPLAY 0.872340 (-8275 3650);
PAINT GREEN (-8275 3650);
DISPLAY INVISIBLE (-8275 3650);
FORCEPROP 1 LAST OFFPAGE TRUE
J 0
(-8050 3600);
DISPLAY 0.872340 (-8050 3600);
PAINT GREEN (-8050 3600);
DISPLAY INVISIBLE (-8050 3600);
FORCEPROP 2 LAST CDS_LIB mstr_standard
J 0
(-8375 3725);
DISPLAY 0.723404 (-8375 3725);
PAINT MONO (-8375 3725);
DISPLAY INVISIBLE (-8375 3725);
FORCEADD TAP..1
R 2
(-7775 4125);
FORCEPROP 3 LASTPIN (-7725 4125) SIG_NAME M_B_CPU1_SA_CB<7>
J 0
(-7715 4135);
DISPLAY 0.659574 (-7715 4135);
PAINT MONO (-7715 4135);
DISPLAY INVISIBLE (-7715 4135);
FORCEPROP 1 LASTPIN (-7725 4125) BN 7
J 2
(-7713 4133);
DISPLAY 0.489362 (-7713 4133);
PAINT GREEN (-7713 4133);
FORCEPROP 2 LAST CDS_LIB mstr_standard
J 0
(-7775 4125);
DISPLAY 0.723404 (-7775 4125);
PAINT MONO (-7775 4125);
DISPLAY INVISIBLE (-7775 4125);
FORCEPROP 1 LAST BODY_TYPE PLUMBING
J 2
(-7775 4175);
DISPLAY 0.872340 (-7775 4175);
PAINT GREEN (-7775 4175);
DISPLAY INVISIBLE (-7775 4175);
FORCEPROP 1 LAST HDL_TAP TRUE
J 2
(-8100 4000);
DISPLAY 0.872340 (-8100 4000);
DISPLAY INVISIBLE (-8100 4000);
FORCEPROP 1 LAST PATH I81
J 2
(-7773 4125);
DISPLAY 0.872340 (-7773 4125);
PAINT GREEN (-7773 4125);
DISPLAY INVISIBLE (-7773 4125);
FORCEADD TAP..1
R 2
(-7775 4825);
FORCEPROP 3 LASTPIN (-7725 4825) SIG_NAME M_B_CPU1_SB_CA<0>
J 0
(-7715 4835);
DISPLAY 0.659574 (-7715 4835);
PAINT MONO (-7715 4835);
DISPLAY INVISIBLE (-7715 4835);
FORCEPROP 1 LASTPIN (-7725 4825) BN 0
J 2
(-7713 4833);
DISPLAY 0.489362 (-7713 4833);
PAINT GREEN (-7713 4833);
FORCEPROP 2 LAST CDS_LIB mstr_standard
J 0
(-7775 4825);
DISPLAY 0.723404 (-7775 4825);
PAINT MONO (-7775 4825);
DISPLAY INVISIBLE (-7775 4825);
FORCEPROP 1 LAST BODY_TYPE PLUMBING
J 2
(-7775 4875);
DISPLAY 0.872340 (-7775 4875);
PAINT GREEN (-7775 4875);
DISPLAY INVISIBLE (-7775 4875);
FORCEPROP 1 LAST HDL_TAP TRUE
J 2
(-8100 4700);
DISPLAY 0.872340 (-8100 4700);
DISPLAY INVISIBLE (-8100 4700);
FORCEPROP 1 LAST PATH I82
J 2
(-7773 4825);
DISPLAY 0.872340 (-7773 4825);
PAINT GREEN (-7773 4825);
DISPLAY INVISIBLE (-7773 4825);
FORCEADD TAP..1
R 2
(-7775 4875);
FORCEPROP 3 LASTPIN (-7725 4875) SIG_NAME M_B_CPU1_SB_CA<1>
J 0
(-7715 4885);
DISPLAY 0.659574 (-7715 4885);
PAINT MONO (-7715 4885);
DISPLAY INVISIBLE (-7715 4885);
FORCEPROP 1 LASTPIN (-7725 4875) BN 1
J 2
(-7713 4883);
DISPLAY 0.489362 (-7713 4883);
PAINT GREEN (-7713 4883);
FORCEPROP 2 LAST CDS_LIB mstr_standard
J 0
(-7775 4875);
DISPLAY 0.723404 (-7775 4875);
PAINT MONO (-7775 4875);
DISPLAY INVISIBLE (-7775 4875);
FORCEPROP 1 LAST BODY_TYPE PLUMBING
J 2
(-7775 4925);
DISPLAY 0.872340 (-7775 4925);
PAINT GREEN (-7775 4925);
DISPLAY INVISIBLE (-7775 4925);
FORCEPROP 1 LAST HDL_TAP TRUE
J 2
(-8100 4750);
DISPLAY 0.872340 (-8100 4750);
DISPLAY INVISIBLE (-8100 4750);
FORCEPROP 1 LAST PATH I83
J 2
(-7773 4875);
DISPLAY 0.872340 (-7773 4875);
PAINT GREEN (-7773 4875);
DISPLAY INVISIBLE (-7773 4875);
FORCEADD TAP..1
R 2
(-7775 4925);
FORCEPROP 3 LASTPIN (-7725 4925) SIG_NAME M_B_CPU1_SB_CA<2>
J 0
(-7715 4935);
DISPLAY 0.659574 (-7715 4935);
PAINT MONO (-7715 4935);
DISPLAY INVISIBLE (-7715 4935);
FORCEPROP 1 LASTPIN (-7725 4925) BN 2
J 2
(-7713 4933);
DISPLAY 0.489362 (-7713 4933);
PAINT GREEN (-7713 4933);
FORCEPROP 2 LAST CDS_LIB mstr_standard
J 0
(-7775 4925);
DISPLAY 0.723404 (-7775 4925);
PAINT MONO (-7775 4925);
DISPLAY INVISIBLE (-7775 4925);
FORCEPROP 1 LAST BODY_TYPE PLUMBING
J 2
(-7775 4975);
DISPLAY 0.872340 (-7775 4975);
PAINT GREEN (-7775 4975);
DISPLAY INVISIBLE (-7775 4975);
FORCEPROP 1 LAST HDL_TAP TRUE
J 2
(-8100 4800);
DISPLAY 0.872340 (-8100 4800);
DISPLAY INVISIBLE (-8100 4800);
FORCEPROP 1 LAST PATH I84
J 2
(-7773 4925);
DISPLAY 0.872340 (-7773 4925);
PAINT GREEN (-7773 4925);
DISPLAY INVISIBLE (-7773 4925);
FORCEADD TAP..1
R 2
(-7775 4975);
FORCEPROP 3 LASTPIN (-7725 4975) SIG_NAME M_B_CPU1_SB_CA<3>
J 0
(-7715 4985);
DISPLAY 0.659574 (-7715 4985);
PAINT MONO (-7715 4985);
DISPLAY INVISIBLE (-7715 4985);
FORCEPROP 1 LASTPIN (-7725 4975) BN 3
J 2
(-7713 4983);
DISPLAY 0.489362 (-7713 4983);
PAINT GREEN (-7713 4983);
FORCEPROP 2 LAST CDS_LIB mstr_standard
J 0
(-7775 4975);
DISPLAY 0.723404 (-7775 4975);
PAINT MONO (-7775 4975);
DISPLAY INVISIBLE (-7775 4975);
FORCEPROP 1 LAST BODY_TYPE PLUMBING
J 2
(-7775 5025);
DISPLAY 0.872340 (-7775 5025);
PAINT GREEN (-7775 5025);
DISPLAY INVISIBLE (-7775 5025);
FORCEPROP 1 LAST HDL_TAP TRUE
J 2
(-8100 4850);
DISPLAY 0.872340 (-8100 4850);
DISPLAY INVISIBLE (-8100 4850);
FORCEPROP 1 LAST PATH I85
J 2
(-7773 4975);
DISPLAY 0.872340 (-7773 4975);
PAINT GREEN (-7773 4975);
DISPLAY INVISIBLE (-7773 4975);
FORCEADD TAP..1
R 2
(-7775 5075);
FORCEPROP 3 LASTPIN (-7725 5075) SIG_NAME M_B_CPU1_SB_CA<5>
J 0
(-7715 5085);
DISPLAY 0.659574 (-7715 5085);
PAINT MONO (-7715 5085);
DISPLAY INVISIBLE (-7715 5085);
FORCEPROP 1 LASTPIN (-7725 5075) BN 5
J 2
(-7713 5083);
DISPLAY 0.489362 (-7713 5083);
PAINT GREEN (-7713 5083);
FORCEPROP 2 LAST CDS_LIB mstr_standard
J 0
(-7775 5075);
DISPLAY 0.723404 (-7775 5075);
PAINT MONO (-7775 5075);
DISPLAY INVISIBLE (-7775 5075);
FORCEPROP 1 LAST BODY_TYPE PLUMBING
J 2
(-7775 5125);
DISPLAY 0.872340 (-7775 5125);
PAINT GREEN (-7775 5125);
DISPLAY INVISIBLE (-7775 5125);
FORCEPROP 1 LAST HDL_TAP TRUE
J 2
(-8100 4950);
DISPLAY 0.872340 (-8100 4950);
DISPLAY INVISIBLE (-8100 4950);
FORCEPROP 1 LAST PATH I86
J 2
(-7773 5075);
DISPLAY 0.872340 (-7773 5075);
PAINT GREEN (-7773 5075);
DISPLAY INVISIBLE (-7773 5075);
FORCEADD TAP..1
R 2
(-7775 5025);
FORCEPROP 3 LASTPIN (-7725 5025) SIG_NAME M_B_CPU1_SB_CA<4>
J 0
(-7715 5035);
DISPLAY 0.659574 (-7715 5035);
PAINT MONO (-7715 5035);
DISPLAY INVISIBLE (-7715 5035);
FORCEPROP 1 LASTPIN (-7725 5025) BN 4
J 2
(-7713 5033);
DISPLAY 0.489362 (-7713 5033);
PAINT GREEN (-7713 5033);
FORCEPROP 2 LAST CDS_LIB mstr_standard
J 0
(-7775 5025);
DISPLAY 0.723404 (-7775 5025);
PAINT MONO (-7775 5025);
DISPLAY INVISIBLE (-7775 5025);
FORCEPROP 1 LAST BODY_TYPE PLUMBING
J 2
(-7775 5075);
DISPLAY 0.872340 (-7775 5075);
PAINT GREEN (-7775 5075);
DISPLAY INVISIBLE (-7775 5075);
FORCEPROP 1 LAST HDL_TAP TRUE
J 2
(-8100 4900);
DISPLAY 0.872340 (-8100 4900);
DISPLAY INVISIBLE (-8100 4900);
FORCEPROP 1 LAST PATH I87
J 2
(-7773 5025);
DISPLAY 0.872340 (-7773 5025);
PAINT GREEN (-7773 5025);
DISPLAY INVISIBLE (-7773 5025);
FORCEADD TAP..1
R 2
(-7775 5225);
FORCEPROP 3 LASTPIN (-7725 5225) SIG_NAME M_B_CPU1_SA_CA<0>
J 0
(-7715 5235);
DISPLAY 0.659574 (-7715 5235);
PAINT MONO (-7715 5235);
DISPLAY INVISIBLE (-7715 5235);
FORCEPROP 1 LASTPIN (-7725 5225) BN 0
J 2
(-7713 5233);
DISPLAY 0.489362 (-7713 5233);
PAINT GREEN (-7713 5233);
FORCEPROP 2 LAST CDS_LIB mstr_standard
J 0
(-7775 5225);
DISPLAY 0.723404 (-7775 5225);
PAINT MONO (-7775 5225);
DISPLAY INVISIBLE (-7775 5225);
FORCEPROP 1 LAST BODY_TYPE PLUMBING
J 2
(-7775 5275);
DISPLAY 0.872340 (-7775 5275);
PAINT GREEN (-7775 5275);
DISPLAY INVISIBLE (-7775 5275);
FORCEPROP 1 LAST HDL_TAP TRUE
J 2
(-8100 5100);
DISPLAY 0.872340 (-8100 5100);
DISPLAY INVISIBLE (-8100 5100);
FORCEPROP 1 LAST PATH I88
J 2
(-7773 5225);
DISPLAY 0.872340 (-7773 5225);
PAINT GREEN (-7773 5225);
DISPLAY INVISIBLE (-7773 5225);
FORCEADD TAP..1
R 2
(-7775 5125);
FORCEPROP 3 LASTPIN (-7725 5125) SIG_NAME M_B_CPU1_SB_CA<6>
J 0
(-7715 5135);
DISPLAY 0.659574 (-7715 5135);
PAINT MONO (-7715 5135);
DISPLAY INVISIBLE (-7715 5135);
FORCEPROP 1 LASTPIN (-7725 5125) BN 6
J 2
(-7713 5133);
DISPLAY 0.489362 (-7713 5133);
PAINT GREEN (-7713 5133);
FORCEPROP 2 LAST CDS_LIB mstr_standard
J 0
(-7775 5125);
DISPLAY 0.723404 (-7775 5125);
PAINT MONO (-7775 5125);
DISPLAY INVISIBLE (-7775 5125);
FORCEPROP 1 LAST BODY_TYPE PLUMBING
J 2
(-7775 5175);
DISPLAY 0.872340 (-7775 5175);
PAINT GREEN (-7775 5175);
DISPLAY INVISIBLE (-7775 5175);
FORCEPROP 1 LAST HDL_TAP TRUE
J 2
(-8100 5000);
DISPLAY 0.872340 (-8100 5000);
DISPLAY INVISIBLE (-8100 5000);
FORCEPROP 1 LAST PATH I89
J 2
(-7773 5125);
DISPLAY 0.872340 (-7773 5125);
PAINT GREEN (-7773 5125);
DISPLAY INVISIBLE (-7773 5125);
FORCEADD OFFPAGE..5
(-8200 3175);
FORCEPROP 2 LAST $XR0 38 
J 0
(-8424 3175);
DISPLAY 0.638298 (-8424 3175);
PAINT MONO (-8424 3175);
FORCEPROP 2 LAST PATH I9
J 0
(-8450 3225);
DISPLAY 1.021277 (-8450 3225);
DISPLAY INVISIBLE (-8450 3225);
FORCEPROP 1 LAST COMMENT_BODY TRUE
J 0
(-8100 3100);
DISPLAY 0.872340 (-8100 3100);
PAINT GREEN (-8100 3100);
DISPLAY INVISIBLE (-8100 3100);
FORCEPROP 1 LAST OFFPAGE TRUE
J 0
(-7875 3050);
DISPLAY 0.872340 (-7875 3050);
PAINT GREEN (-7875 3050);
DISPLAY INVISIBLE (-7875 3050);
FORCEPROP 2 LAST CDS_LIB mstr_standard
J 0
(-8200 3175);
DISPLAY INVISIBLE (-8200 3175);
FORCEADD TAP..1
R 2
(-7775 5275);
FORCEPROP 3 LASTPIN (-7725 5275) SIG_NAME M_B_CPU1_SA_CA<1>
J 0
(-7715 5285);
DISPLAY 0.659574 (-7715 5285);
PAINT MONO (-7715 5285);
DISPLAY INVISIBLE (-7715 5285);
FORCEPROP 1 LASTPIN (-7725 5275) BN 1
J 2
(-7713 5283);
DISPLAY 0.489362 (-7713 5283);
PAINT GREEN (-7713 5283);
FORCEPROP 2 LAST CDS_LIB mstr_standard
J 0
(-7775 5275);
DISPLAY 0.723404 (-7775 5275);
PAINT MONO (-7775 5275);
DISPLAY INVISIBLE (-7775 5275);
FORCEPROP 1 LAST BODY_TYPE PLUMBING
J 2
(-7775 5325);
DISPLAY 0.872340 (-7775 5325);
PAINT GREEN (-7775 5325);
DISPLAY INVISIBLE (-7775 5325);
FORCEPROP 1 LAST HDL_TAP TRUE
J 2
(-8100 5150);
DISPLAY 0.872340 (-8100 5150);
DISPLAY INVISIBLE (-8100 5150);
FORCEPROP 1 LAST PATH I90
J 2
(-7773 5275);
DISPLAY 0.872340 (-7773 5275);
PAINT GREEN (-7773 5275);
DISPLAY INVISIBLE (-7773 5275);
FORCEADD TAP..1
R 2
(-7775 5325);
FORCEPROP 3 LASTPIN (-7725 5325) SIG_NAME M_B_CPU1_SA_CA<2>
J 0
(-7715 5335);
DISPLAY 0.659574 (-7715 5335);
PAINT MONO (-7715 5335);
DISPLAY INVISIBLE (-7715 5335);
FORCEPROP 1 LASTPIN (-7725 5325) BN 2
J 2
(-7713 5333);
DISPLAY 0.489362 (-7713 5333);
PAINT GREEN (-7713 5333);
FORCEPROP 2 LAST CDS_LIB mstr_standard
J 0
(-7775 5325);
DISPLAY 0.723404 (-7775 5325);
PAINT MONO (-7775 5325);
DISPLAY INVISIBLE (-7775 5325);
FORCEPROP 1 LAST BODY_TYPE PLUMBING
J 2
(-7775 5375);
DISPLAY 0.872340 (-7775 5375);
PAINT GREEN (-7775 5375);
DISPLAY INVISIBLE (-7775 5375);
FORCEPROP 1 LAST HDL_TAP TRUE
J 2
(-8100 5200);
DISPLAY 0.872340 (-8100 5200);
DISPLAY INVISIBLE (-8100 5200);
FORCEPROP 1 LAST PATH I91
J 2
(-7773 5325);
DISPLAY 0.872340 (-7773 5325);
PAINT GREEN (-7773 5325);
DISPLAY INVISIBLE (-7773 5325);
FORCEADD TAP..1
R 2
(-7775 5375);
FORCEPROP 3 LASTPIN (-7725 5375) SIG_NAME M_B_CPU1_SA_CA<3>
J 0
(-7715 5385);
DISPLAY 0.659574 (-7715 5385);
PAINT MONO (-7715 5385);
DISPLAY INVISIBLE (-7715 5385);
FORCEPROP 1 LASTPIN (-7725 5375) BN 3
J 2
(-7713 5383);
DISPLAY 0.489362 (-7713 5383);
PAINT GREEN (-7713 5383);
FORCEPROP 2 LAST CDS_LIB mstr_standard
J 0
(-7775 5375);
DISPLAY 0.723404 (-7775 5375);
PAINT MONO (-7775 5375);
DISPLAY INVISIBLE (-7775 5375);
FORCEPROP 1 LAST BODY_TYPE PLUMBING
J 2
(-7775 5425);
DISPLAY 0.872340 (-7775 5425);
PAINT GREEN (-7775 5425);
DISPLAY INVISIBLE (-7775 5425);
FORCEPROP 1 LAST HDL_TAP TRUE
J 2
(-8100 5250);
DISPLAY 0.872340 (-8100 5250);
DISPLAY INVISIBLE (-8100 5250);
FORCEPROP 1 LAST PATH I92
J 2
(-7773 5375);
DISPLAY 0.872340 (-7773 5375);
PAINT GREEN (-7773 5375);
DISPLAY INVISIBLE (-7773 5375);
FORCEADD TAP..1
R 2
(-7775 5425);
FORCEPROP 3 LASTPIN (-7725 5425) SIG_NAME M_B_CPU1_SA_CA<4>
J 0
(-7715 5435);
DISPLAY 0.659574 (-7715 5435);
PAINT MONO (-7715 5435);
DISPLAY INVISIBLE (-7715 5435);
FORCEPROP 1 LASTPIN (-7725 5425) BN 4
J 2
(-7713 5433);
DISPLAY 0.489362 (-7713 5433);
PAINT GREEN (-7713 5433);
FORCEPROP 2 LAST CDS_LIB mstr_standard
J 0
(-7775 5425);
DISPLAY 0.723404 (-7775 5425);
PAINT MONO (-7775 5425);
DISPLAY INVISIBLE (-7775 5425);
FORCEPROP 1 LAST BODY_TYPE PLUMBING
J 2
(-7775 5475);
DISPLAY 0.872340 (-7775 5475);
PAINT GREEN (-7775 5475);
DISPLAY INVISIBLE (-7775 5475);
FORCEPROP 1 LAST HDL_TAP TRUE
J 2
(-8100 5300);
DISPLAY 0.872340 (-8100 5300);
DISPLAY INVISIBLE (-8100 5300);
FORCEPROP 1 LAST PATH I93
J 2
(-7773 5425);
DISPLAY 0.872340 (-7773 5425);
PAINT GREEN (-7773 5425);
DISPLAY INVISIBLE (-7773 5425);
FORCEADD TAP..1
R 2
(-7775 5475);
FORCEPROP 3 LASTPIN (-7725 5475) SIG_NAME M_B_CPU1_SA_CA<5>
J 0
(-7715 5485);
DISPLAY 0.659574 (-7715 5485);
PAINT MONO (-7715 5485);
DISPLAY INVISIBLE (-7715 5485);
FORCEPROP 1 LASTPIN (-7725 5475) BN 5
J 2
(-7713 5483);
DISPLAY 0.489362 (-7713 5483);
PAINT GREEN (-7713 5483);
FORCEPROP 2 LAST CDS_LIB mstr_standard
J 0
(-7775 5475);
DISPLAY 0.723404 (-7775 5475);
PAINT MONO (-7775 5475);
DISPLAY INVISIBLE (-7775 5475);
FORCEPROP 1 LAST BODY_TYPE PLUMBING
J 2
(-7775 5525);
DISPLAY 0.872340 (-7775 5525);
PAINT GREEN (-7775 5525);
DISPLAY INVISIBLE (-7775 5525);
FORCEPROP 1 LAST HDL_TAP TRUE
J 2
(-8100 5350);
DISPLAY 0.872340 (-8100 5350);
DISPLAY INVISIBLE (-8100 5350);
FORCEPROP 1 LAST PATH I94
J 2
(-7773 5475);
DISPLAY 0.872340 (-7773 5475);
PAINT GREEN (-7773 5475);
DISPLAY INVISIBLE (-7773 5475);
FORCEADD TAP..1
R 2
(-7775 5525);
FORCEPROP 3 LASTPIN (-7725 5525) SIG_NAME M_B_CPU1_SA_CA<6>
J 0
(-7715 5535);
DISPLAY 0.659574 (-7715 5535);
PAINT MONO (-7715 5535);
DISPLAY INVISIBLE (-7715 5535);
FORCEPROP 1 LASTPIN (-7725 5525) BN 6
J 2
(-7713 5533);
DISPLAY 0.489362 (-7713 5533);
PAINT GREEN (-7713 5533);
FORCEPROP 2 LAST CDS_LIB mstr_standard
J 0
(-7775 5525);
DISPLAY 0.723404 (-7775 5525);
PAINT MONO (-7775 5525);
DISPLAY INVISIBLE (-7775 5525);
FORCEPROP 1 LAST BODY_TYPE PLUMBING
J 2
(-7775 5575);
DISPLAY 0.872340 (-7775 5575);
PAINT GREEN (-7775 5575);
DISPLAY INVISIBLE (-7775 5575);
FORCEPROP 1 LAST HDL_TAP TRUE
J 2
(-8100 5400);
DISPLAY 0.872340 (-8100 5400);
DISPLAY INVISIBLE (-8100 5400);
FORCEPROP 1 LAST PATH I95
J 2
(-7773 5525);
DISPLAY 0.872340 (-7773 5525);
PAINT GREEN (-7773 5525);
DISPLAY INVISIBLE (-7773 5525);
FORCEADD TAP..1
(-6075 4125);
FORCEPROP 3 LASTPIN (-6125 4125) SIG_NAME M_B_CPU1_SA_DQ<3>
J 0
(-6115 4135);
DISPLAY 0.659574 (-6115 4135);
PAINT MONO (-6115 4135);
DISPLAY INVISIBLE (-6115 4135);
FORCEPROP 1 LASTPIN (-6125 4125) BN 3
J 0
(-6137 4133);
DISPLAY 0.489362 (-6137 4133);
PAINT GREEN (-6137 4133);
FORCEPROP 2 LAST CDS_LIB mstr_standard
J 0
(-6075 4125);
DISPLAY 0.723404 (-6075 4125);
PAINT MONO (-6075 4125);
DISPLAY INVISIBLE (-6075 4125);
FORCEPROP 1 LAST BODY_TYPE PLUMBING
J 0
(-6075 4175);
DISPLAY 0.872340 (-6075 4175);
PAINT GREEN (-6075 4175);
DISPLAY INVISIBLE (-6075 4175);
FORCEPROP 1 LAST HDL_TAP TRUE
J 0
(-5750 4000);
DISPLAY 0.872340 (-5750 4000);
DISPLAY INVISIBLE (-5750 4000);
FORCEPROP 1 LAST PATH I96
J 0
(-6077 4125);
DISPLAY 0.872340 (-6077 4125);
PAINT GREEN (-6077 4125);
DISPLAY INVISIBLE (-6077 4125);
FORCEADD TAP..1
(-6075 4175);
FORCEPROP 3 LASTPIN (-6125 4175) SIG_NAME M_B_CPU1_SA_DQ<4>
J 0
(-6115 4185);
DISPLAY 0.659574 (-6115 4185);
PAINT MONO (-6115 4185);
DISPLAY INVISIBLE (-6115 4185);
FORCEPROP 1 LASTPIN (-6125 4175) BN 4
J 0
(-6137 4183);
DISPLAY 0.489362 (-6137 4183);
PAINT GREEN (-6137 4183);
FORCEPROP 2 LAST CDS_LIB mstr_standard
J 0
(-6075 4175);
DISPLAY 0.723404 (-6075 4175);
PAINT MONO (-6075 4175);
DISPLAY INVISIBLE (-6075 4175);
FORCEPROP 1 LAST BODY_TYPE PLUMBING
J 0
(-6075 4225);
DISPLAY 0.872340 (-6075 4225);
PAINT GREEN (-6075 4225);
DISPLAY INVISIBLE (-6075 4225);
FORCEPROP 1 LAST HDL_TAP TRUE
J 0
(-5750 4050);
DISPLAY 0.872340 (-5750 4050);
DISPLAY INVISIBLE (-5750 4050);
FORCEPROP 1 LAST PATH I97
J 0
(-6077 4175);
DISPLAY 0.872340 (-6077 4175);
PAINT GREEN (-6077 4175);
DISPLAY INVISIBLE (-6077 4175);
FORCEADD TAP..1
(-6075 4225);
FORCEPROP 3 LASTPIN (-6125 4225) SIG_NAME M_B_CPU1_SA_DQ<5>
J 0
(-6115 4235);
DISPLAY 0.659574 (-6115 4235);
PAINT MONO (-6115 4235);
DISPLAY INVISIBLE (-6115 4235);
FORCEPROP 1 LASTPIN (-6125 4225) BN 5
J 0
(-6137 4233);
DISPLAY 0.489362 (-6137 4233);
PAINT GREEN (-6137 4233);
FORCEPROP 2 LAST CDS_LIB mstr_standard
J 0
(-6075 4225);
DISPLAY 0.723404 (-6075 4225);
PAINT MONO (-6075 4225);
DISPLAY INVISIBLE (-6075 4225);
FORCEPROP 1 LAST BODY_TYPE PLUMBING
J 0
(-6075 4275);
DISPLAY 0.872340 (-6075 4275);
PAINT GREEN (-6075 4275);
DISPLAY INVISIBLE (-6075 4275);
FORCEPROP 1 LAST HDL_TAP TRUE
J 0
(-5750 4100);
DISPLAY 0.872340 (-5750 4100);
DISPLAY INVISIBLE (-5750 4100);
FORCEPROP 1 LAST PATH I98
J 0
(-6077 4225);
DISPLAY 0.872340 (-6077 4225);
PAINT GREEN (-6077 4225);
DISPLAY INVISIBLE (-6077 4225);
FORCEADD TAP..1
(-6075 4275);
FORCEPROP 3 LASTPIN (-6125 4275) SIG_NAME M_B_CPU1_SA_DQ<6>
J 0
(-6115 4285);
DISPLAY 0.659574 (-6115 4285);
PAINT MONO (-6115 4285);
DISPLAY INVISIBLE (-6115 4285);
FORCEPROP 1 LASTPIN (-6125 4275) BN 6
J 0
(-6137 4283);
DISPLAY 0.489362 (-6137 4283);
PAINT GREEN (-6137 4283);
FORCEPROP 2 LAST CDS_LIB mstr_standard
J 0
(-6075 4275);
DISPLAY 0.723404 (-6075 4275);
PAINT MONO (-6075 4275);
DISPLAY INVISIBLE (-6075 4275);
FORCEPROP 1 LAST BODY_TYPE PLUMBING
J 0
(-6075 4325);
DISPLAY 0.872340 (-6075 4325);
PAINT GREEN (-6075 4325);
DISPLAY INVISIBLE (-6075 4325);
FORCEPROP 1 LAST HDL_TAP TRUE
J 0
(-5750 4150);
DISPLAY 0.872340 (-5750 4150);
DISPLAY INVISIBLE (-5750 4150);
FORCEPROP 1 LAST PATH I99
J 0
(-6077 4275);
DISPLAY 0.872340 (-6077 4275);
PAINT GREEN (-6077 4275);
DISPLAY INVISIBLE (-6077 4275);
FORCEADD QUANTA_TITLE_BLOCK_C..1
(-100 100);
FORCEPROP 0 LAST CDS_CON_LAST_MODIFIED Fri Mar 11 14:53:02 2022
J 0
(-1985 115);
DISPLAY INVISIBLE (-1985 115);
FORCEPROP 1 LAST CUSTOM_TXT_CDS <CON_LAST_MODIFIED>
J 0
(-1985 115);
DISPLAY 0.978723 (-1985 115);
FORCEPROP 2 LAST CUSTOM_TXT_CDS <XR_PAGE_TITLE>
J 0
(-7990 5350);
DISPLAY 0.638298 (-7990 5350);
PAINT PINK (-7990 5350);
DISPLAY INVISIBLE (-7990 5350);
FORCEPROP 1 LAST CUSTOM_TXT_CDS <NAME_2>
J 0
(-3275 150);
FORCEPROP 1 LAST CUSTOM_TXT_CDS <NAME_1>
J 0
(-3275 275);
FORCEPROP 1 LAST CUSTOM_TXT_CDS <Q_NUMBER>
J 0
(-1503 203);
DISPLAY 1.212766 (-1503 203);
FORCEPROP 1 LAST CUSTOM_TXT_CDS <Q_PROJ>
J 0
(-2482 202);
DISPLAY 1.212766 (-2482 202);
FORCEPROP 1 LAST CUSTOM_TXT_CDS <Q_REV>
J 0
(-284 203);
DISPLAY 1.212766 (-284 203);
FORCEPROP 1 LAST CUSTOM_TXT_CDS <CON_PAGE_NUM> OF <CON_TOTAL_PAGES>
J 0
(-546 118);
DISPLAY 0.978723 (-546 118);
FORCEPROP 1 LAST Q_TITLE DDR5 - CPU1 CHB
J 0
(-9375 150);
DISPLAY 2.446809 (-9375 150);
PAINT GREEN (-9375 150);
FORCEPROP 1 LAST Q_DEPT BU9
J 1
(-3863 149);
DISPLAY 1.957447 (-3863 149);
PAINT GREEN (-3863 149);
FORCEPROP 2 LAST PAGE_BORDER TRUE
J 0
(-7990 5350);
DISPLAY 0.638298 (-7990 5350);
PAINT PINK (-7990 5350);
DISPLAY INVISIBLE (-7990 5350);
FORCEPROP 2 LAST CDS_LIB pure_quanta
J 0
(-100 100);
DISPLAY INVISIBLE (-100 100);
FORCEPROP 1 LAST CDS_LMAN_SYM_OUTLINE -9475,6775,100,-125
J 0
(-100 100);
DISPLAY 0.468085 (-100 100);
PAINT GREEN (-100 100);
DISPLAY INVISIBLE (-100 100);
FORCEPROP 1 LAST COMMENT_BODY TRUE
J 0
(-88 87);
DISPLAY 0.978723 (-88 87);
PAINT GREEN (-88 87);
DISPLAY INVISIBLE (-88 87);
FORCEPROP 2 LAST CDS_XR_PAGE_TITLE CR-98 : @T6G_MB_LIB.T6G(SCH_1):PAGE98
J 0
(-7990 5350);
DISPLAY 0.638298 (-7990 5350);
PAINT PINK (-7990 5350);
DISPLAY INVISIBLE (-7990 5350);
FORCEADD DNS..2
(-8475 2425);
PAINT RED (-8475 2425);
FORCEPROP 2 LAST CDS_LIB mstr_misc
J 0
(-8475 2425);
DISPLAY INVISIBLE (-8475 2425);
FORCEPROP 1 LAST COMMENT_BODY TRUE
R 1
J 0
(-8400 2200);
DISPLAY 0.872340 (-8400 2200);
PAINT PEACH (-8400 2200);
DISPLAY INVISIBLE (-8400 2200);
WIRE 17 -1 (-7825 4150)(-7825 4175);
WIRE 17 -1 (-7825 4150)(-7825 4100);
WIRE 17 -1 (-7825 4175)(-8325 4175);
FORCEPROP 2 LAST SIG_NAME M_B_CPU1_SA_CB<7:0>
J 0
(-8275 4185);
DISPLAY 0.489362 (-8275 4185);
WIRE 17 -1 (-7825 3950)(-7825 4000);
WIRE 17 -1 (-7825 3900)(-7825 3950);
WIRE 17 -1 (-7825 4050)(-7825 4000);
WIRE 17 -1 (-7825 4050)(-7825 4100);
WIRE 17 -1 (-7825 3850)(-7825 3900);
WIRE 17 -1 (-7825 3800)(-7825 3850);
WIRE 17 -1 (-7825 3700)(-7825 3725);
WIRE 17 -1 (-7825 3700)(-7825 3650);
WIRE 17 -1 (-7825 3725)(-8325 3725);
FORCEPROP 2 LAST SIG_NAME M_B_CPU1_SB_CB<7:0>
J 0
(-8275 3735);
DISPLAY 0.489362 (-8275 3735);
WIRE 17 -1 (-7825 4850)(-7825 4900);
WIRE 17 -1 (-7825 4900)(-7825 4950);
WIRE 17 -1 (-7825 4950)(-7825 5000);
WIRE 17 -1 (-7825 5000)(-7825 5050);
WIRE 17 -1 (-7825 5050)(-7825 5100);
WIRE 17 -1 (-7825 5100)(-7825 5150);
WIRE 17 -1 (-7825 5150)(-7825 5175);
WIRE 17 -1 (-7825 5175)(-8325 5175);
FORCEPROP 2 LAST SIG_NAME M_B_CPU1_SB_CA<6:0>
J 0
(-8310 5185);
DISPLAY 0.489362 (-8310 5185);
WIRE 17 -1 (-7825 5300)(-7825 5350);
WIRE 17 -1 (-7825 5250)(-7825 5300);
WIRE 17 -1 (-7825 5350)(-7825 5400);
WIRE 17 -1 (-7825 5400)(-7825 5450);
WIRE 17 -1 (-7825 5450)(-7825 5500);
WIRE 17 -1 (-7825 5500)(-7825 5550);
WIRE 17 -1 (-7825 5550)(-7825 5575);
WIRE 17 -1 (-7825 5575)(-8325 5575);
FORCEPROP 2 LAST SIG_NAME M_B_CPU1_SA_CA<6:0>
J 0
(-8310 5585);
DISPLAY 0.489362 (-8310 5585);
WIRE 17 -1 (-7825 3600)(-7825 3650);
WIRE 17 -1 (-7825 3600)(-7825 3550);
WIRE 17 -1 (-7825 3500)(-7825 3550);
WIRE 17 -1 (-7825 3450)(-7825 3500);
WIRE 17 -1 (-7825 3400)(-7825 3450);
WIRE 17 -1 (-7825 3350)(-7825 3400);
WIRE 17 -1 (-6025 5500)(-6025 5450);
WIRE 17 -1 (-6025 5550)(-6025 5500);
WIRE 17 -1 (-6025 5450)(-6025 5400);
WIRE 17 -1 (-6025 5400)(-6025 5350);
WIRE 17 -1 (-6025 5575)(-6025 5550);
WIRE 17 -1 (-6025 5575)(-5375 5575);
FORCEPROP 2 LAST SIG_NAME M_B_CPU1_SA_DQ<31:0>
J 0
(-5960 5585);
DISPLAY 0.489362 (-5960 5585);
WIRE 17 -1 (-6025 5350)(-6025 5300);
WIRE 17 -1 (-6025 5300)(-6025 5250);
WIRE 17 -1 (-6025 5250)(-6025 5200);
WIRE 17 -1 (-6025 5200)(-6025 5150);
WIRE 17 -1 (-6025 5150)(-6025 5100);
WIRE 17 -1 (-6025 5100)(-6025 5050);
WIRE 17 -1 (-6025 5050)(-6025 5000);
WIRE 17 -1 (-6025 5000)(-6025 4950);
WIRE 17 -1 (-6025 4950)(-6025 4900);
WIRE 17 -1 (-6025 4900)(-6025 4850);
WIRE 17 -1 (-6025 4850)(-6025 4800);
WIRE 17 -1 (-6025 4750)(-6025 4800);
WIRE 17 -1 (-6025 4700)(-6025 4750);
WIRE 17 -1 (-6025 4650)(-6025 4700);
WIRE 17 -1 (-6025 4600)(-6025 4650);
WIRE 17 -1 (-6025 4600)(-6025 4550);
WIRE 17 -1 (-6025 4550)(-6025 4500);
WIRE 17 -1 (-6025 4500)(-6025 4450);
WIRE 17 -1 (-6025 4450)(-6025 4400);
WIRE 17 -1 (-6025 4400)(-6025 4350);
WIRE 17 -1 (-6025 4350)(-6025 4300);
WIRE 17 -1 (-6025 4300)(-6025 4250);
WIRE 17 -1 (-6025 4250)(-6025 4200);
WIRE 17 -1 (-6025 4150)(-6025 4200);
WIRE 17 -1 (-6025 4100)(-6025 4150);
WIRE 17 -1 (-6025 4050)(-6025 4100);
WIRE 17 -1 (-6025 4000)(-6025 4050);
WIRE 17 -1 (-6025 3925)(-6025 3900);
WIRE 17 -1 (-6025 3925)(-5375 3925);
FORCEPROP 2 LAST SIG_NAME M_B_CPU1_SB_DQ<31:0>
J 0
(-5960 3935);
DISPLAY 0.489362 (-5960 3935);
WIRE 17 -1 (-6025 3850)(-6025 3800);
WIRE 17 -1 (-6025 3900)(-6025 3850);
WIRE 17 -1 (-6025 3800)(-6025 3750);
WIRE 17 -1 (-6025 3750)(-6025 3700);
WIRE 17 -1 (-6025 3700)(-6025 3650);
WIRE 17 -1 (-6025 3650)(-6025 3600);
WIRE 17 -1 (-6025 3600)(-6025 3550);
WIRE 17 -1 (-6025 3550)(-6025 3500);
WIRE 17 -1 (-6025 3500)(-6025 3450);
WIRE 17 -1 (-6025 3450)(-6025 3400);
WIRE 17 -1 (-6025 3400)(-6025 3350);
WIRE 17 -1 (-6025 3350)(-6025 3300);
WIRE 17 -1 (-6025 3300)(-6025 3250);
WIRE 17 -1 (-6025 3250)(-6025 3200);
WIRE 17 -1 (-6025 3200)(-6025 3150);
WIRE 17 -1 (-6025 3100)(-6025 3150);
WIRE 17 -1 (-6025 3050)(-6025 3100);
WIRE 17 -1 (-6025 3000)(-6025 3050);
WIRE 17 -1 (-6025 2950)(-6025 3000);
WIRE 17 -1 (-6025 2950)(-6025 2900);
WIRE 17 -1 (-6025 2900)(-6025 2850);
WIRE 17 -1 (-6025 2850)(-6025 2800);
WIRE 17 -1 (-6025 2800)(-6025 2750);
WIRE 17 -1 (-6025 2750)(-6025 2700);
WIRE 17 -1 (-6025 2700)(-6025 2650);
WIRE 17 -1 (-6025 2650)(-6025 2600);
WIRE 17 -1 (-6025 2600)(-6025 2550);
WIRE 17 -1 (-6025 2500)(-6025 2550);
WIRE 17 -1 (-6025 2450)(-6025 2500);
WIRE 17 -1 (-6025 2400)(-6025 2450);
WIRE 17 -1 (-6025 2350)(-6025 2400);
WIRE 17 -1 (-3200 4275)(-3200 4175);
WIRE 17 -1 (-3200 4375)(-3200 4275);
WIRE 17 -1 (-3200 4175)(-3200 4075);
WIRE 17 -1 (-3200 3975)(-3200 4075);
WIRE 17 -1 (-3200 4475)(-3200 4375);
WIRE 17 -1 (-3200 4500)(-3200 4475);
WIRE 17 -1 (-3200 3875)(-3200 3975);
WIRE 17 -1 (-3200 3775)(-3200 3875);
WIRE 17 -1 (-3200 4500)(-2500 4500);
FORCEPROP 2 LAST SIG_NAME M_B_CPU1_SA_DQS_DN<9:0>
J 0
(-3135 4510);
DISPLAY 0.489362 (-3135 4510);
WIRE 17 -1 (-3400 4225)(-3400 4125);
WIRE 17 -1 (-3400 4325)(-3400 4225);
WIRE 17 -1 (-3400 4025)(-3400 4125);
WIRE 17 -1 (-3400 3925)(-3400 4025);
WIRE 17 -1 (-3400 4425)(-3400 4325);
WIRE 17 -1 (-3400 4525)(-3400 4425);
WIRE 17 -1 (-3400 3825)(-3400 3925);
WIRE 17 -1 (-3400 3825)(-3400 3725);
WIRE 17 -1 (-3400 4550)(-3400 4525);
WIRE 17 -1 (-3400 4550)(-2500 4550);
FORCEPROP 2 LAST SIG_NAME M_B_CPU1_SA_DQS_DP<9:0>
J 0
(-3135 4560);
DISPLAY 0.489362 (-3135 4560);
WIRE 17 -1 (-3400 3375)(-3400 3275);
WIRE 17 -1 (-3400 3475)(-3400 3375);
WIRE 17 -1 (-3400 3275)(-3400 3175);
WIRE 17 -1 (-3400 3175)(-3400 3075);
WIRE 17 -1 (-3400 3500)(-3400 3475);
WIRE 17 -1 (-3400 3500)(-2500 3500);
FORCEPROP 2 LAST SIG_NAME M_B_CPU1_SB_DQS_DP<9:0>
J 0
(-3135 3510);
DISPLAY 0.489362 (-3135 3510);
WIRE 17 -1 (-3200 3325)(-3200 3225);
WIRE 17 -1 (-3200 3425)(-3200 3325);
WIRE 17 -1 (-3200 3225)(-3200 3125);
WIRE 17 -1 (-3200 3125)(-3200 3025);
WIRE 17 -1 (-3200 3450)(-3200 3425);
WIRE 17 -1 (-3200 3450)(-2500 3450);
FORCEPROP 2 LAST SIG_NAME M_B_CPU1_SB_DQS_DN<9:0>
J 0
(-3135 3460);
DISPLAY 0.489362 (-3135 3460);
WIRE 17 -1 (-3400 2975)(-3400 3075);
WIRE 17 -1 (-3400 2875)(-3400 2975);
WIRE 17 -1 (-3400 2775)(-3400 2875);
WIRE 17 -1 (-3200 3675)(-3200 3575);
WIRE 17 -1 (-3200 3775)(-3200 3675);
WIRE 17 -1 (-3400 3725)(-3400 3625);
WIRE 17 -1 (-3200 2625)(-3200 2525);
WIRE 17 -1 (-3200 2725)(-3200 2625);
WIRE 17 -1 (-3200 2725)(-3200 2825);
WIRE 17 -1 (-3200 2825)(-3200 2925);
WIRE 17 -1 (-3200 2925)(-3200 3025);
WIRE 17 -1 (-3400 2675)(-3400 2575);
WIRE 17 -1 (-3400 2775)(-3400 2675);
WIRE 16 -1 (-6475 1275)(-6475 1350);
WIRE 16 -1 (-8725 3150)(-8725 3225);
WIRE 16 -1 (-8500 2525)(-8500 2550);
WIRE 16 -1 (-7925 2825)(-8350 2825);
FORCEPROP 2 LAST SIG_NAME I3C_SPD_DDRAF_CPU1_SCL
J 0
(-8410 2835);
DISPLAY 0.489362 (-8410 2835);
WIRE 16 -1 (-7625 2925)(-7625 2825);
WIRE 16 -1 (-7525 2925)(-7625 2925);
FORCEPROP 2 LAST SIG_NAME I3C_SPD_DDRB_CPU1_SCL
J 0
(-8010 2935);
DISPLAY 0.446809 (-8010 2935);
FORCEPROP 2 LASTPROP $XRERR UNIQUE?
J 0
(-8250 2935);
DISPLAY 0.638298 (-8250 2935);
PAINT MONO (-8250 2935);
DISPLAY INVISIBLE (-8250 2935);
WIRE 16 -1 (-7625 2825)(-7725 2825);
WIRE 16 -1 (-8300 2275)(-8500 2275);
WIRE 16 -1 (-8300 2275)(-8300 2675);
WIRE 16 -1 (-8500 2325)(-8500 2275);
WIRE 16 -1 (-8500 2275)(-8525 2275);
WIRE 16 -1 (-7525 2675)(-8300 2675);
FORCEPROP 2 LAST SIG_NAME PWRGD_CHB_CPU1_DIMM
J 0
(-8100 2685);
DISPLAY 0.489362 (-8100 2685);
FORCEPROP 2 LASTPROP $XRERR UNIQUE?
J 0
(-8340 2685);
DISPLAY 0.638298 (-8340 2685);
PAINT MONO (-8340 2685);
DISPLAY INVISIBLE (-8340 2685);
WIRE 16 -1 (-7525 2525)(-8125 2525);
FORCEPROP 2 LAST SIG_NAME TP_CHB_CPU1_DIMM_RFU_5
J 0
(-8135 2535);
DISPLAY 0.489362 (-8135 2535);
FORCEPROP 2 LASTPROP $XRERR UNIQUE?
J 0
(-8365 2525);
DISPLAY 0.638298 (-8365 2525);
PAINT MONO (-8365 2525);
DISPLAY INVISIBLE (-8365 2525);
WIRE 16 -1 (-7525 2575)(-8125 2575);
FORCEPROP 2 LAST SIG_NAME TP_CHB_CPU1_DIMM_RFU_6
J 0
(-8135 2585);
DISPLAY 0.489362 (-8135 2585);
FORCEPROP 2 LASTPROP $XRERR UNIQUE?
J 0
(-8365 2575);
DISPLAY 0.638298 (-8365 2575);
PAINT MONO (-8365 2575);
DISPLAY INVISIBLE (-8365 2575);
WIRE 16 -1 (-7525 2975)(-8325 2975);
FORCEPROP 2 LAST SIG_NAME I3C_SPD_DDRAF_CPU1_SDA
J 0
(-8335 2985);
DISPLAY 0.489362 (-8335 2985);
WIRE 16 -1 (-7525 3025)(-8325 3025);
FORCEPROP 2 LAST SIG_NAME PD_CHB_CPU1_DIMM_SAA
J 0
(-8300 3035);
DISPLAY 0.489362 (-8300 3035);
WIRE 16 -1 (-8625 3075)(-7525 3075);
WIRE 16 -1 (-8625 3450)(-8625 3075);
WIRE 16 -1 (-8625 3500)(-8625 3450);
WIRE 16 -1 (-8725 3450)(-8625 3450);
WIRE 16 -1 (-8725 3425)(-8725 3450);
WIRE 16 -1 (-7525 3175)(-8150 3175);
FORCEPROP 2 LAST SIG_NAME M_B_CPU1_ALERT_N
J 0
(-8135 3185);
DISPLAY 0.489362 (-8135 3185);
WIRE 16 -1 (-7525 2375)(-8125 2375);
FORCEPROP 2 LAST SIG_NAME TP_CHB_CPU1_DIMM_RFU_2
J 0
(-8135 2385);
DISPLAY 0.489362 (-8135 2385);
FORCEPROP 2 LASTPROP $XRERR UNIQUE?
J 0
(-8365 2375);
DISPLAY 0.638298 (-8365 2375);
PAINT MONO (-8365 2375);
DISPLAY INVISIBLE (-8365 2375);
WIRE 16 -1 (-7525 5225)(-7725 5225);
WIRE 16 -1 (-1875 5025)(-2175 5025);
WIRE 16 -1 (-2175 5025)(-2175 5075);
WIRE 16 -1 (-1875 5075)(-2175 5075);
WIRE 16 -1 (-2175 5075)(-2175 5125);
WIRE 16 -1 (-1875 5125)(-2175 5125);
WIRE 16 -1 (-2175 5125)(-2175 5725);
WIRE 16 -1 (-2300 5725)(-2175 5725);
WIRE 16 -1 (-2300 5725)(-2875 5725);
WIRE 16 -1 (-2300 5725)(-2300 5625);
WIRE 16 -1 (-2875 5725)(-2875 5800);
WIRE 16 -1 (-2875 5625)(-2875 5725);
WIRE 16 -1 (-2300 5300)(-2875 5300);
WIRE 16 -1 (-2300 5300)(-2300 5425);
WIRE 16 -1 (-2875 5300)(-2875 5425);
WIRE 16 -1 (-2875 5300)(-2875 5225);
WIRE 16 -1 (-375 5125)(-675 5125);
WIRE 16 -1 (-375 5125)(-375 5075);
WIRE 16 -1 (-375 5075)(-375 5025);
WIRE 16 -1 (-375 5075)(-675 5075);
WIRE 16 -1 (-375 5025)(-375 4975);
WIRE 16 -1 (-375 5025)(-675 5025);
WIRE 16 -1 (-375 4975)(-375 4925);
WIRE 16 -1 (-375 4975)(-675 4975);
WIRE 16 -1 (-375 4925)(-375 4875);
WIRE 16 -1 (-375 4925)(-675 4925);
WIRE 16 -1 (-375 4875)(-375 4825);
WIRE 16 -1 (-375 4875)(-675 4875);
WIRE 16 -1 (-375 4825)(-375 4775);
WIRE 16 -1 (-375 4825)(-675 4825);
WIRE 16 -1 (-375 4775)(-375 4725);
WIRE 16 -1 (-375 4775)(-675 4775);
WIRE 16 -1 (-375 4725)(-375 4675);
WIRE 16 -1 (-375 4725)(-675 4725);
WIRE 16 -1 (-375 4675)(-375 4625);
WIRE 16 -1 (-375 4675)(-675 4675);
WIRE 16 -1 (-375 4625)(-375 4575);
WIRE 16 -1 (-375 4625)(-675 4625);
WIRE 16 -1 (-375 4575)(-375 4525);
WIRE 16 -1 (-375 4575)(-675 4575);
WIRE 16 -1 (-375 4525)(-375 4475);
WIRE 16 -1 (-375 4525)(-675 4525);
WIRE 16 -1 (-375 4475)(-375 4425);
WIRE 16 -1 (-375 4475)(-675 4475);
WIRE 16 -1 (-375 4425)(-375 4375);
WIRE 16 -1 (-375 4425)(-675 4425);
WIRE 16 -1 (-375 4375)(-375 4325);
WIRE 16 -1 (-375 4375)(-675 4375);
WIRE 16 -1 (-375 4325)(-375 4275);
WIRE 16 -1 (-375 4325)(-675 4325);
WIRE 16 -1 (-375 4275)(-375 4225);
WIRE 16 -1 (-375 4275)(-675 4275);
WIRE 16 -1 (-375 4225)(-375 4175);
WIRE 16 -1 (-375 4225)(-675 4225);
WIRE 16 -1 (-375 4175)(-375 4125);
WIRE 16 -1 (-375 4175)(-675 4175);
WIRE 16 -1 (-375 4125)(-675 4125);
WIRE 16 -1 (-375 4125)(-375 4075);
WIRE 16 -1 (-375 4075)(-375 4025);
WIRE 16 -1 (-375 4075)(-675 4075);
WIRE 16 -1 (-375 4025)(-375 3975);
WIRE 16 -1 (-375 4025)(-675 4025);
WIRE 16 -1 (-375 3975)(-375 3925);
WIRE 16 -1 (-375 3975)(-675 3975);
WIRE 16 -1 (-375 3925)(-375 3875);
WIRE 16 -1 (-375 3925)(-675 3925);
WIRE 16 -1 (-375 3875)(-375 3825);
WIRE 16 -1 (-375 3875)(-675 3875);
WIRE 16 -1 (-375 3825)(-375 3775);
WIRE 16 -1 (-375 3825)(-675 3825);
WIRE 16 -1 (-375 3775)(-375 3725);
WIRE 16 -1 (-375 3775)(-675 3775);
WIRE 16 -1 (-375 3725)(-375 3675);
WIRE 16 -1 (-375 3725)(-675 3725);
WIRE 16 -1 (-375 3675)(-375 3625);
WIRE 16 -1 (-375 3675)(-675 3675);
WIRE 16 -1 (-375 3625)(-375 3575);
WIRE 16 -1 (-375 3625)(-675 3625);
WIRE 16 -1 (-375 3575)(-375 3525);
WIRE 16 -1 (-375 3575)(-675 3575);
WIRE 16 -1 (-375 3525)(-375 3475);
WIRE 16 -1 (-375 3525)(-675 3525);
WIRE 16 -1 (-375 3475)(-375 3425);
WIRE 16 -1 (-375 3475)(-675 3475);
WIRE 16 -1 (-375 3425)(-375 3375);
WIRE 16 -1 (-375 3425)(-675 3425);
WIRE 16 -1 (-375 3375)(-375 3325);
WIRE 16 -1 (-375 3375)(-675 3375);
WIRE 16 -1 (-375 3325)(-375 3275);
WIRE 16 -1 (-375 3325)(-675 3325);
WIRE 16 -1 (-375 3275)(-375 3225);
WIRE 16 -1 (-375 3275)(-675 3275);
WIRE 16 -1 (-375 3225)(-375 3175);
WIRE 16 -1 (-375 3225)(-675 3225);
WIRE 16 -1 (-375 3175)(-375 3125);
WIRE 16 -1 (-375 3175)(-675 3175);
WIRE 16 -1 (-375 3125)(-375 3075);
WIRE 16 -1 (-375 3125)(-675 3125);
WIRE 16 -1 (-375 3075)(-675 3075);
WIRE 16 -1 (-375 3075)(-375 3025);
WIRE 16 -1 (-375 3025)(-375 2975);
WIRE 16 -1 (-375 3025)(-675 3025);
WIRE 16 -1 (-375 2975)(-375 2925);
WIRE 16 -1 (-375 2975)(-675 2975);
WIRE 16 -1 (-375 2925)(-375 2875);
WIRE 16 -1 (-375 2925)(-675 2925);
WIRE 16 -1 (-375 2875)(-375 2825);
WIRE 16 -1 (-375 2875)(-675 2875);
WIRE 16 -1 (-375 2825)(-375 2775);
WIRE 16 -1 (-375 2825)(-675 2825);
WIRE 16 -1 (-375 2775)(-375 2725);
WIRE 16 -1 (-375 2775)(-675 2775);
WIRE 16 -1 (-375 2725)(-375 2675);
WIRE 16 -1 (-375 2725)(-675 2725);
WIRE 16 -1 (-375 2675)(-375 2625);
WIRE 16 -1 (-375 2675)(-675 2675);
WIRE 16 -1 (-375 2625)(-375 2575);
WIRE 16 -1 (-375 2625)(-675 2625);
WIRE 16 -1 (-375 2575)(-375 2525);
WIRE 16 -1 (-375 2575)(-675 2575);
WIRE 16 -1 (-375 2525)(-375 2475);
WIRE 16 -1 (-375 2525)(-675 2525);
WIRE 16 -1 (-375 2475)(-375 2425);
WIRE 16 -1 (-375 2475)(-675 2475);
WIRE 16 -1 (-375 2425)(-375 2375);
WIRE 16 -1 (-375 2425)(-675 2425);
WIRE 16 -1 (-375 2375)(-375 2325);
WIRE 16 -1 (-375 2375)(-675 2375);
WIRE 16 -1 (-375 2325)(-375 2275);
WIRE 16 -1 (-375 2325)(-675 2325);
WIRE 16 -1 (-375 2275)(-375 2225);
WIRE 16 -1 (-375 2275)(-675 2275);
WIRE 16 -1 (-375 2225)(-375 2175);
WIRE 16 -1 (-375 2225)(-675 2225);
WIRE 16 -1 (-375 2175)(-375 2125);
WIRE 16 -1 (-375 2175)(-675 2175);
WIRE 16 -1 (-375 2125)(-375 2075);
WIRE 16 -1 (-375 2125)(-675 2125);
WIRE 16 -1 (-375 2075)(-375 2025);
WIRE 16 -1 (-375 2075)(-675 2075);
WIRE 16 -1 (-375 2025)(-375 1975);
WIRE 16 -1 (-375 2025)(-675 2025);
WIRE 16 -1 (-375 1975)(-375 1875);
WIRE 16 -1 (-375 1975)(-675 1975);
WIRE 16 -1 (-375 1875)(-375 1825);
WIRE 16 -1 (-375 1875)(-675 1875);
WIRE 16 -1 (-375 1825)(-375 1775);
WIRE 16 -1 (-375 1825)(-675 1825);
WIRE 16 -1 (-375 1775)(-375 1600);
WIRE 16 -1 (-375 1775)(-675 1775);
WIRE 16 -1 (-1875 1875)(-2175 1875);
WIRE 16 -1 (-2175 1925)(-2175 1875);
WIRE 16 -1 (-2175 1875)(-2175 1775);
WIRE 16 -1 (-1875 1925)(-2175 1925);
WIRE 16 -1 (-2175 1975)(-2175 1925);
WIRE 16 -1 (-1875 1975)(-2175 1975);
WIRE 16 -1 (-2175 2025)(-2175 1975);
WIRE 16 -1 (-1875 2025)(-2175 2025);
WIRE 16 -1 (-2175 2075)(-2175 2025);
WIRE 16 -1 (-1875 2075)(-2175 2075);
WIRE 16 -1 (-2175 2125)(-2175 2075);
WIRE 16 -1 (-1875 2125)(-2175 2125);
WIRE 16 -1 (-2175 2175)(-2175 2125);
WIRE 16 -1 (-1875 2175)(-2175 2175);
WIRE 16 -1 (-2175 2225)(-2175 2175);
WIRE 16 -1 (-1875 2225)(-2175 2225);
WIRE 16 -1 (-2175 2275)(-2175 2225);
WIRE 16 -1 (-1875 2275)(-2175 2275);
WIRE 16 -1 (-2175 2325)(-2175 2275);
WIRE 16 -1 (-1875 2325)(-2175 2325);
WIRE 16 -1 (-2175 2375)(-2175 2325);
WIRE 16 -1 (-1875 2375)(-2175 2375);
WIRE 16 -1 (-2175 2425)(-2175 2375);
WIRE 16 -1 (-1875 2425)(-2175 2425);
WIRE 16 -1 (-2175 2475)(-2175 2425);
WIRE 16 -1 (-1875 2475)(-2175 2475);
WIRE 16 -1 (-2175 2525)(-2175 2475);
WIRE 16 -1 (-1875 2525)(-2175 2525);
WIRE 16 -1 (-2175 2575)(-2175 2525);
WIRE 16 -1 (-1875 2575)(-2175 2575);
WIRE 16 -1 (-2175 2625)(-2175 2575);
WIRE 16 -1 (-1875 2625)(-2175 2625);
WIRE 16 -1 (-2175 2675)(-2175 2625);
WIRE 16 -1 (-1875 2675)(-2175 2675);
WIRE 16 -1 (-2175 2725)(-2175 2675);
WIRE 16 -1 (-1875 2725)(-2175 2725);
WIRE 16 -1 (-2175 2775)(-2175 2725);
WIRE 16 -1 (-1875 2775)(-2175 2775);
WIRE 16 -1 (-2175 2825)(-2175 2775);
WIRE 16 -1 (-1875 2825)(-2175 2825);
WIRE 16 -1 (-2175 2875)(-2175 2825);
WIRE 16 -1 (-1875 2875)(-2175 2875);
WIRE 16 -1 (-2175 2925)(-2175 2875);
WIRE 16 -1 (-1875 2925)(-2175 2925);
WIRE 16 -1 (-2175 2975)(-2175 2925);
WIRE 16 -1 (-1875 2975)(-2175 2975);
WIRE 16 -1 (-2175 3025)(-2175 2975);
WIRE 16 -1 (-1875 3025)(-2175 3025);
WIRE 16 -1 (-2175 3075)(-2175 3025);
WIRE 16 -1 (-1875 3075)(-2175 3075);
WIRE 16 -1 (-2175 3125)(-2175 3075);
WIRE 16 -1 (-1875 3125)(-2175 3125);
WIRE 16 -1 (-2175 3175)(-2175 3125);
WIRE 16 -1 (-1875 3175)(-2175 3175);
WIRE 16 -1 (-2175 3225)(-2175 3175);
WIRE 16 -1 (-1875 3225)(-2175 3225);
WIRE 16 -1 (-2175 3275)(-2175 3225);
WIRE 16 -1 (-1875 3275)(-2175 3275);
WIRE 16 -1 (-2175 3325)(-2175 3275);
WIRE 16 -1 (-1875 3325)(-2175 3325);
WIRE 16 -1 (-2175 3375)(-2175 3325);
WIRE 16 -1 (-1875 3375)(-2175 3375);
WIRE 16 -1 (-2175 3425)(-2175 3375);
WIRE 16 -1 (-1875 3425)(-2175 3425);
WIRE 16 -1 (-2175 3475)(-2175 3425);
WIRE 16 -1 (-1875 3475)(-2175 3475);
WIRE 16 -1 (-2175 3525)(-2175 3475);
WIRE 16 -1 (-1875 3525)(-2175 3525);
WIRE 16 -1 (-2175 3575)(-2175 3525);
WIRE 16 -1 (-1875 3575)(-2175 3575);
WIRE 16 -1 (-2175 3625)(-2175 3575);
WIRE 16 -1 (-1875 3625)(-2175 3625);
WIRE 16 -1 (-2175 3675)(-2175 3625);
WIRE 16 -1 (-1875 3675)(-2175 3675);
WIRE 16 -1 (-2175 3725)(-2175 3675);
WIRE 16 -1 (-1875 3725)(-2175 3725);
WIRE 16 -1 (-2175 3775)(-2175 3725);
WIRE 16 -1 (-1875 3775)(-2175 3775);
WIRE 16 -1 (-2175 3825)(-2175 3775);
WIRE 16 -1 (-1875 3825)(-2175 3825);
WIRE 16 -1 (-2175 3875)(-2175 3825);
WIRE 16 -1 (-1875 3875)(-2175 3875);
WIRE 16 -1 (-2175 3925)(-2175 3875);
WIRE 16 -1 (-1875 3925)(-2175 3925);
WIRE 16 -1 (-2175 3975)(-2175 3925);
WIRE 16 -1 (-1875 3975)(-2175 3975);
WIRE 16 -1 (-2175 4025)(-2175 3975);
WIRE 16 -1 (-1875 4025)(-2175 4025);
WIRE 16 -1 (-2175 4075)(-2175 4025);
WIRE 16 -1 (-2175 4125)(-2175 4075);
WIRE 16 -1 (-1875 4075)(-2175 4075);
WIRE 16 -1 (-1875 4125)(-2175 4125);
WIRE 16 -1 (-2175 4175)(-2175 4125);
WIRE 16 -1 (-1875 4175)(-2175 4175);
WIRE 16 -1 (-2175 4225)(-2175 4175);
WIRE 16 -1 (-1875 4225)(-2175 4225);
WIRE 16 -1 (-2175 4275)(-2175 4225);
WIRE 16 -1 (-1875 4275)(-2175 4275);
WIRE 16 -1 (-2175 4325)(-2175 4275);
WIRE 16 -1 (-1875 4325)(-2175 4325);
WIRE 16 -1 (-2175 4375)(-2175 4325);
WIRE 16 -1 (-1875 4375)(-2175 4375);
WIRE 16 -1 (-2175 4425)(-2175 4375);
WIRE 16 -1 (-1875 4425)(-2175 4425);
WIRE 16 -1 (-2175 4475)(-2175 4425);
WIRE 16 -1 (-1875 4475)(-2175 4475);
WIRE 16 -1 (-2175 4525)(-2175 4475);
WIRE 16 -1 (-1875 4525)(-2175 4525);
WIRE 16 -1 (-2175 4575)(-2175 4525);
WIRE 16 -1 (-1875 4575)(-2175 4575);
WIRE 16 -1 (-2175 4625)(-2175 4575);
WIRE 16 -1 (-1875 4625)(-2175 4625);
WIRE 16 -1 (-2175 4675)(-2175 4625);
WIRE 16 -1 (-1875 4675)(-2175 4675);
WIRE 16 -1 (-2175 4725)(-2175 4675);
WIRE 16 -1 (-1875 4725)(-2175 4725);
WIRE 16 -1 (-2175 4775)(-2175 4725);
WIRE 16 -1 (-1875 4775)(-2175 4775);
WIRE 16 -1 (-2175 4825)(-2175 4775);
WIRE 16 -1 (-1875 4825)(-2175 4825);
WIRE 16 -1 (-2175 4875)(-2175 4825);
WIRE 16 -1 (-1875 4875)(-2175 4875);
WIRE 16 -1 (-2175 4925)(-2175 4875);
WIRE 16 -1 (-1875 4925)(-2175 4925);
WIRE 16 -1 (-2175 4975)(-2175 4925);
WIRE 16 -1 (-1875 4975)(-2175 4975);
WIRE 16 -1 (-3500 4300)(-3650 4300);
WIRE 16 -1 (-3650 4350)(-3300 4350);
WIRE 16 -1 (-6125 5375)(-6325 5375);
WIRE 16 -1 (-6325 4925)(-6125 4925);
WIRE 16 -1 (-3650 4500)(-3500 4500);
WIRE 16 -1 (-3650 3450)(-3500 3450);
WIRE 16 -1 (-3650 3400)(-3300 3400);
WIRE 16 -1 (-3650 4450)(-3300 4450);
WIRE 16 -1 (-3500 4400)(-3650 4400);
WIRE 16 -1 (-3650 3200)(-3300 3200);
WIRE 16 -1 (-3500 3150)(-3650 3150);
WIRE 16 -1 (-3650 3100)(-3300 3100);
WIRE 16 -1 (-3650 4150)(-3300 4150);
WIRE 16 -1 (-3650 3050)(-3500 3050);
WIRE 16 -1 (-3650 3000)(-3300 3000);
WIRE 16 -1 (-3650 4100)(-3500 4100);
WIRE 16 -1 (-3650 4050)(-3300 4050);
WIRE 16 -1 (-3500 2950)(-3650 2950);
WIRE 16 -1 (-3650 2900)(-3300 2900);
WIRE 16 -1 (-3500 4000)(-3650 4000);
WIRE 16 -1 (-3650 3950)(-3300 3950);
WIRE 16 -1 (-3500 2850)(-3650 2850);
WIRE 16 -1 (-3650 2800)(-3300 2800);
WIRE 16 -1 (-3500 3900)(-3650 3900);
WIRE 16 -1 (-3650 3850)(-3300 3850);
WIRE 16 -1 (-3500 2750)(-3650 2750);
WIRE 16 -1 (-3650 2700)(-3300 2700);
WIRE 16 -1 (-3500 3800)(-3650 3800);
WIRE 16 -1 (-3650 3750)(-3300 3750);
WIRE 16 -1 (-3650 2650)(-3500 2650);
WIRE 16 -1 (-3650 2600)(-3300 2600);
WIRE 16 -1 (-3650 3700)(-3500 3700);
WIRE 16 -1 (-3650 3650)(-3300 3650);
WIRE 16 -1 (-3500 2550)(-3650 2550);
WIRE 16 -1 (-3650 2500)(-3300 2500);
WIRE 16 -1 (-3500 3600)(-3650 3600);
WIRE 16 -1 (-3650 3550)(-3300 3550);
WIRE 16 -1 (-3500 3250)(-3650 3250);
WIRE 16 -1 (-3650 3300)(-3300 3300);
WIRE 16 -1 (-3500 3350)(-3650 3350);
WIRE 16 -1 (-3500 4200)(-3650 4200);
WIRE 16 -1 (-3650 4250)(-3300 4250);
WIRE 16 -1 (-7525 5275)(-7725 5275);
WIRE 16 -1 (-7525 5425)(-7725 5425);
WIRE 16 -1 (-6325 5525)(-6125 5525);
WIRE 16 -1 (-6125 5425)(-6325 5425);
WIRE 16 -1 (-6125 5175)(-6325 5175);
WIRE 16 -1 (-7525 2275)(-8125 2275);
FORCEPROP 2 LAST SIG_NAME TP_CHB_CPU1_DIMM_RFU_0
J 0
(-8135 2285);
DISPLAY 0.489362 (-8135 2285);
FORCEPROP 2 LASTPROP $XRERR UNIQUE?
J 0
(-8365 2275);
DISPLAY 0.638298 (-8365 2275);
PAINT MONO (-8365 2275);
DISPLAY INVISIBLE (-8365 2275);
WIRE 16 -1 (-7525 2325)(-8125 2325);
FORCEPROP 2 LAST SIG_NAME TP_CHB_CPU1_DIMM_RFU_1
J 0
(-8135 2335);
DISPLAY 0.489362 (-8135 2335);
FORCEPROP 2 LASTPROP $XRERR UNIQUE?
J 0
(-8365 2325);
DISPLAY 0.638298 (-8365 2325);
PAINT MONO (-8365 2325);
DISPLAY INVISIBLE (-8365 2325);
WIRE 16 -1 (-7525 2425)(-8125 2425);
FORCEPROP 2 LAST SIG_NAME TP_CHB_CPU1_DIMM_RFU_3
J 0
(-8135 2435);
DISPLAY 0.489362 (-8135 2435);
FORCEPROP 2 LASTPROP $XRERR UNIQUE?
J 0
(-8365 2425);
DISPLAY 0.638298 (-8365 2425);
PAINT MONO (-8365 2425);
DISPLAY INVISIBLE (-8365 2425);
WIRE 16 -1 (-7525 2475)(-8125 2475);
FORCEPROP 2 LAST SIG_NAME TP_CHB_CPU1_DIMM_RFU_4
J 0
(-8135 2485);
DISPLAY 0.489362 (-8135 2485);
FORCEPROP 2 LASTPROP $XRERR UNIQUE?
J 0
(-8365 2475);
DISPLAY 0.638298 (-8365 2475);
PAINT MONO (-8365 2475);
DISPLAY INVISIBLE (-8365 2475);
WIRE 16 -1 (-7525 3225)(-8150 3225);
FORCEPROP 2 LAST SIG_NAME M_B_CPU1_RESET_N
J 0
(-8135 3235);
DISPLAY 0.489362 (-8135 3235);
WIRE 16 -1 (-7525 4675)(-8325 4675);
FORCEPROP 2 LAST SIG_NAME M_B_CPU1_SB_PAR
J 0
(-8275 4685);
DISPLAY 0.489362 (-8275 4685);
WIRE 16 -1 (-7525 4725)(-8325 4725);
FORCEPROP 2 LAST SIG_NAME M_B_CPU1_SA_PAR
J 0
(-8275 4735);
DISPLAY 0.489362 (-8275 4735);
WIRE 16 -1 (-7525 2075)(-8325 2075);
FORCEPROP 2 LAST SIG_NAME M_B_CPU1_SB_RSP<0>
J 0
(-8275 2085);
DISPLAY 0.489362 (-8275 2085);
WIRE 16 -1 (-7525 2125)(-8325 2125);
FORCEPROP 2 LAST SIG_NAME M_B_CPU1_SA_RSP<0>
J 0
(-8275 2135);
DISPLAY 0.489362 (-8275 2135);
WIRE 16 -1 (-6125 2325)(-6325 2325);
WIRE 16 -1 (-6125 2375)(-6325 2375);
WIRE 16 -1 (-6125 2425)(-6325 2425);
WIRE 16 -1 (-6325 2475)(-6125 2475);
WIRE 16 -1 (-6125 2525)(-6325 2525);
WIRE 16 -1 (-6125 2575)(-6325 2575);
WIRE 16 -1 (-6125 2625)(-6325 2625);
WIRE 16 -1 (-6325 2675)(-6125 2675);
WIRE 16 -1 (-6125 2725)(-6325 2725);
WIRE 16 -1 (-6125 2775)(-6325 2775);
WIRE 16 -1 (-6125 2825)(-6325 2825);
WIRE 16 -1 (-6325 2875)(-6125 2875);
WIRE 16 -1 (-6125 2925)(-6325 2925);
WIRE 16 -1 (-6125 2975)(-6325 2975);
WIRE 16 -1 (-6125 3025)(-6325 3025);
WIRE 16 -1 (-6325 3075)(-6125 3075);
WIRE 16 -1 (-6125 3125)(-6325 3125);
WIRE 16 -1 (-6125 3175)(-6325 3175);
WIRE 16 -1 (-6125 3225)(-6325 3225);
WIRE 16 -1 (-6325 3275)(-6125 3275);
WIRE 16 -1 (-6125 3325)(-6325 3325);
WIRE 16 -1 (-6125 3375)(-6325 3375);
WIRE 16 -1 (-6125 3425)(-6325 3425);
WIRE 16 -1 (-6325 3475)(-6125 3475);
WIRE 16 -1 (-6125 3525)(-6325 3525);
WIRE 16 -1 (-6125 3575)(-6325 3575);
WIRE 16 -1 (-6125 3625)(-6325 3625);
WIRE 16 -1 (-6325 3675)(-6125 3675);
WIRE 16 -1 (-6125 3725)(-6325 3725);
WIRE 16 -1 (-6125 3775)(-6325 3775);
WIRE 16 -1 (-6125 3825)(-6325 3825);
WIRE 16 -1 (-6325 3875)(-6125 3875);
WIRE 16 -1 (-6125 3975)(-6325 3975);
WIRE 16 -1 (-6125 4025)(-6325 4025);
WIRE 16 -1 (-6125 4075)(-6325 4075);
WIRE 16 -1 (-6325 4125)(-6125 4125);
WIRE 16 -1 (-6125 4175)(-6325 4175);
WIRE 16 -1 (-6125 4225)(-6325 4225);
WIRE 16 -1 (-6125 4275)(-6325 4275);
WIRE 16 -1 (-6325 4325)(-6125 4325);
WIRE 16 -1 (-6125 4375)(-6325 4375);
WIRE 16 -1 (-6125 4425)(-6325 4425);
WIRE 16 -1 (-6125 4475)(-6325 4475);
WIRE 16 -1 (-6325 4525)(-6125 4525);
WIRE 16 -1 (-6125 4575)(-6325 4575);
WIRE 16 -1 (-6125 4625)(-6325 4625);
WIRE 16 -1 (-6125 4675)(-6325 4675);
WIRE 16 -1 (-6325 4725)(-6125 4725);
WIRE 16 -1 (-6125 4775)(-6325 4775);
WIRE 16 -1 (-6125 4825)(-6325 4825);
WIRE 16 -1 (-6125 4875)(-6325 4875);
WIRE 16 -1 (-6125 4975)(-6325 4975);
WIRE 16 -1 (-6125 5025)(-6325 5025);
WIRE 16 -1 (-6125 5075)(-6325 5075);
WIRE 16 -1 (-6325 5125)(-6125 5125);
WIRE 16 -1 (-6125 5225)(-6325 5225);
WIRE 16 -1 (-6125 5275)(-6325 5275);
WIRE 16 -1 (-6325 5325)(-6125 5325);
WIRE 16 -1 (-6125 5475)(-6325 5475);
WIRE 16 -1 (-7525 4425)(-8325 4425);
FORCEPROP 2 LAST SIG_NAME M_B_CPU1_SB_CS_N<1>
J 0
(-8275 4435);
DISPLAY 0.489362 (-8275 4435);
WIRE 16 -1 (-7525 4575)(-8325 4575);
FORCEPROP 2 LAST SIG_NAME M_B_CPU1_SA_CS_N<1>
J 0
(-8275 4585);
DISPLAY 0.489362 (-8275 4585);
WIRE 16 -1 (-7525 4375)(-8325 4375);
FORCEPROP 2 LAST SIG_NAME M_B_CPU1_SB_CS_N<0>
J 0
(-8275 4385);
DISPLAY 0.489362 (-8275 4385);
WIRE 16 -1 (-7525 4525)(-8325 4525);
FORCEPROP 2 LAST SIG_NAME M_B_CPU1_SA_CS_N<0>
J 0
(-8275 4535);
DISPLAY 0.489362 (-8275 4535);
WIRE 16 -1 (-7525 4275)(-8325 4275);
FORCEPROP 2 LAST SIG_NAME M_B_CPU1_CLK_DP<0>
J 0
(-8275 4285);
DISPLAY 0.489362 (-8275 4285);
WIRE 16 -1 (-7525 4225)(-8325 4225);
FORCEPROP 2 LAST SIG_NAME M_B_CPU1_CLK_DN<0>
J 0
(-8275 4235);
DISPLAY 0.489362 (-8275 4235);
WIRE 16 -1 (-7525 3325)(-7725 3325);
WIRE 16 -1 (-7525 3375)(-7725 3375);
WIRE 16 -1 (-7525 3425)(-7725 3425);
WIRE 16 -1 (-7525 3475)(-7725 3475);
WIRE 16 -1 (-7525 3525)(-7725 3525);
WIRE 16 -1 (-7525 3575)(-7725 3575);
WIRE 16 -1 (-7525 3625)(-7725 3625);
WIRE 16 -1 (-7525 3775)(-7725 3775);
WIRE 16 -1 (-7525 3875)(-7725 3875);
WIRE 16 -1 (-7525 3925)(-7725 3925);
WIRE 16 -1 (-7525 4025)(-7725 4025);
WIRE 16 -1 (-7525 4075)(-7725 4075);
WIRE 16 -1 (-7525 5125)(-7725 5125);
WIRE 16 -1 (-7525 5525)(-7725 5525);
WIRE 16 -1 (-7525 5075)(-7725 5075);
WIRE 16 -1 (-7525 5475)(-7725 5475);
WIRE 16 -1 (-7525 5025)(-7725 5025);
WIRE 16 -1 (-7525 4975)(-7725 4975);
WIRE 16 -1 (-7525 5375)(-7725 5375);
WIRE 16 -1 (-7525 4925)(-7725 4925);
WIRE 16 -1 (-7525 5325)(-7725 5325);
WIRE 16 -1 (-7525 4875)(-7725 4875);
WIRE 16 -1 (-7525 4825)(-7725 4825);
WIRE 16 -1 (-7525 3675)(-7725 3675);
WIRE 16 -1 (-7525 3825)(-7725 3825);
WIRE 16 -1 (-7525 3975)(-7725 3975);
WIRE 16 -1 (-7525 4125)(-7725 4125);
WIRE 16 -1 (-9075 2275)(-8725 2275);
FORCEPROP 2 LAST SIG_NAME PWRGD_CHAF_CPU1
J 0
(-9110 2285);
DISPLAY 0.489362 (-9110 2285);
WIRE 16 -1 (-6475 1625)(-6475 1550);
WIRE 16 -1 (-6475 1625)(-7200 1625);
FORCEPROP 2 LAST SIG_NAME PD_CHB_CPU1_DIMM_SAA
J 0
(-7185 1635);
DISPLAY 0.489362 (-7185 1635);
DOT 1 (-2300 5725);
DOT 1 (-2875 5725);
DOT 1 (-8500 2275);
DOT 1 (-8625 3450);
DOT 1 (-2175 1875);
DOT 1 (-2175 1925);
DOT 1 (-2175 1975);
DOT 1 (-2175 2025);
DOT 1 (-2175 2075);
DOT 1 (-2175 2125);
DOT 1 (-2175 2175);
DOT 1 (-2175 2225);
DOT 1 (-2175 2275);
DOT 1 (-2175 2325);
DOT 1 (-2175 2425);
DOT 1 (-2175 2475);
DOT 1 (-2175 2575);
DOT 1 (-2175 2525);
DOT 1 (-2175 2625);
DOT 1 (-2175 2675);
DOT 1 (-2175 2725);
DOT 1 (-2175 2825);
DOT 1 (-2175 2775);
DOT 1 (-2175 2875);
DOT 1 (-2175 2925);
DOT 1 (-2175 2975);
DOT 1 (-2175 3025);
DOT 1 (-2175 3075);
DOT 1 (-2175 3125);
DOT 1 (-2175 3175);
DOT 1 (-2175 3225);
DOT 1 (-2175 3275);
DOT 1 (-2175 3325);
DOT 1 (-2175 3375);
DOT 1 (-2175 3475);
DOT 1 (-2175 3425);
DOT 1 (-2175 3525);
DOT 1 (-2175 3575);
DOT 1 (-2175 3625);
DOT 1 (-2175 3725);
DOT 1 (-2175 3675);
DOT 1 (-375 1775);
DOT 1 (-375 1825);
DOT 1 (-375 1875);
DOT 1 (-375 1975);
DOT 1 (-375 2025);
DOT 1 (-375 2075);
DOT 1 (-375 2125);
DOT 1 (-375 2175);
DOT 1 (-375 2225);
DOT 1 (-375 2275);
DOT 1 (-375 2325);
DOT 1 (-375 2375);
DOT 1 (-375 2425);
DOT 1 (-375 2475);
DOT 1 (-375 2525);
DOT 1 (-375 2575);
DOT 1 (-375 2625);
DOT 1 (-375 2675);
DOT 1 (-375 2725);
DOT 1 (-375 2825);
DOT 1 (-375 2775);
DOT 1 (-375 2875);
DOT 1 (-375 2925);
DOT 1 (-375 2975);
DOT 1 (-375 3025);
DOT 1 (-375 3075);
DOT 1 (-375 3125);
DOT 1 (-375 3225);
DOT 1 (-375 3175);
DOT 1 (-375 3275);
DOT 1 (-375 3325);
DOT 1 (-375 3375);
DOT 1 (-375 3425);
DOT 1 (-375 3475);
DOT 1 (-375 3525);
DOT 1 (-375 3575);
DOT 1 (-375 3625);
DOT 1 (-375 3725);
DOT 1 (-375 3675);
DOT 1 (-375 3775);
DOT 1 (-2175 3825);
DOT 1 (-2175 3875);
DOT 1 (-2175 3925);
DOT 1 (-2175 3975);
DOT 1 (-2175 4025);
DOT 1 (-2175 4075);
DOT 1 (-2175 4125);
DOT 1 (-2175 4175);
DOT 1 (-2175 4225);
DOT 1 (-2175 4275);
DOT 1 (-2175 4375);
DOT 1 (-2175 4325);
DOT 1 (-2175 4475);
DOT 1 (-2175 4425);
DOT 1 (-2175 4525);
DOT 1 (-2175 4575);
DOT 1 (-2175 4625);
DOT 1 (-2175 4675);
DOT 1 (-2175 4725);
DOT 1 (-2175 4875);
DOT 1 (-2175 4825);
DOT 1 (-2175 4925);
DOT 1 (-375 3825);
DOT 1 (-375 3875);
DOT 1 (-375 3925);
DOT 1 (-375 3975);
DOT 1 (-375 4025);
DOT 1 (-375 4075);
DOT 1 (-375 4125);
DOT 1 (-375 4175);
DOT 1 (-375 4225);
DOT 1 (-375 4275);
DOT 1 (-375 4325);
DOT 1 (-375 4375);
DOT 1 (-375 4425);
DOT 1 (-375 4475);
DOT 1 (-375 4525);
DOT 1 (-375 4575);
DOT 1 (-375 4625);
DOT 1 (-375 4675);
DOT 1 (-375 4725);
DOT 1 (-375 4775);
DOT 1 (-375 4875);
DOT 1 (-375 4825);
DOT 1 (-375 4925);
DOT 1 (-375 4975);
DOT 1 (-375 5025);
DOT 1 (-375 5075);
DOT 1 (-2175 2375);
DOT 1 (-2175 3775);
DOT 1 (-2175 5075);
DOT 1 (-2175 4775);
DOT 1 (-2875 5300);
DOT 1 (-2175 5125);
QUIT
